FILE_TYPE = MACRO_DRAWING;
SET COLOR_WIRE YELLOW;
SET COLOR_PROP MONO;
SET COLOR_DOT WHITE;
SET COLOR_ARC YELLOW;
SET COLOR_BODY GREEN;
SET COLOR_NOTE MONO;
SET PROP_DISPLAY VALUE;
SET PAGE_NUMBER P112;
FORCEADD OFFPAGE..1
(-3200 4025);
FORCEPROP 2 LAST $XR0 111 
J 0
(-3482 4025);
DISPLAY 0.638298 (-3482 4025);
PAINT MONO (-3482 4025);
FORCEPROP 2 LAST $XR1 118 
J 0
(-3602 4025);
DISPLAY 0.638298 (-3602 4025);
PAINT MONO (-3602 4025);
FORCEPROP 2 LAST $XR2 112 
J 0
(-3722 4025);
DISPLAY 0.638298 (-3722 4025);
PAINT MONO (-3722 4025);
FORCEPROP 2 LAST CDS_LIB mstr_standard
J 0
(-3200 4025);
DISPLAY 2.212766 (-3200 4025);
PAINT ORANGE (-3200 4025);
DISPLAY INVISIBLE (-3200 4025);
FORCEPROP 1 LAST OFFPAGE TRUE
J 0
(-2875 3900);
DISPLAY 1.404255 (-2875 3900);
PAINT GREEN (-2875 3900);
DISPLAY INVISIBLE (-2875 3900);
FORCEPROP 1 LAST COMMENT_BODY TRUE
J 0
(-3075 3925);
DISPLAY 1.404255 (-3075 3925);
PAINT PEACH (-3075 3925);
DISPLAY INVISIBLE (-3075 3925);
FORCEPROP 2 LAST PATH I100
J 0
(-3450 4075);
DISPLAY 1.021277 (-3450 4075);
PAINT ORANGE (-3450 4075);
DISPLAY INVISIBLE (-3450 4075);
FORCEADD OFFPAGE..1
(-3200 3875);
FORCEPROP 2 LAST $XR0 118 
J 0
(-3482 3875);
DISPLAY 0.638298 (-3482 3875);
PAINT MONO (-3482 3875);
FORCEPROP 2 LAST $XR1 111 
J 0
(-3602 3875);
DISPLAY 0.638298 (-3602 3875);
PAINT MONO (-3602 3875);
FORCEPROP 2 LAST CDS_LIB mstr_standard
J 0
(-3200 3875);
DISPLAY 2.212766 (-3200 3875);
PAINT ORANGE (-3200 3875);
DISPLAY INVISIBLE (-3200 3875);
FORCEPROP 1 LAST OFFPAGE TRUE
J 0
(-2875 3750);
DISPLAY 1.404255 (-2875 3750);
PAINT GREEN (-2875 3750);
DISPLAY INVISIBLE (-2875 3750);
FORCEPROP 1 LAST COMMENT_BODY TRUE
J 0
(-3075 3775);
DISPLAY 1.404255 (-3075 3775);
PAINT PEACH (-3075 3775);
DISPLAY INVISIBLE (-3075 3775);
FORCEPROP 2 LAST PATH I101
J 0
(-3450 3925);
DISPLAY 1.021277 (-3450 3925);
PAINT ORANGE (-3450 3925);
DISPLAY INVISIBLE (-3450 3925);
FORCEADD OFFPAGE..1
(-3200 3950);
FORCEPROP 2 LAST $XR0 112 
J 0
(-3482 3950);
DISPLAY 0.638298 (-3482 3950);
PAINT MONO (-3482 3950);
FORCEPROP 2 LAST $XR1 118 
J 0
(-3602 3950);
DISPLAY 0.638298 (-3602 3950);
PAINT MONO (-3602 3950);
FORCEPROP 2 LAST $XR2 111 
J 0
(-3722 3950);
DISPLAY 0.638298 (-3722 3950);
PAINT MONO (-3722 3950);
FORCEPROP 2 LAST CDS_LIB mstr_standard
J 0
(-3200 3950);
DISPLAY 2.212766 (-3200 3950);
PAINT ORANGE (-3200 3950);
DISPLAY INVISIBLE (-3200 3950);
FORCEPROP 1 LAST OFFPAGE TRUE
J 0
(-2875 3825);
DISPLAY 1.404255 (-2875 3825);
PAINT GREEN (-2875 3825);
DISPLAY INVISIBLE (-2875 3825);
FORCEPROP 1 LAST COMMENT_BODY TRUE
J 0
(-3075 3850);
DISPLAY 1.404255 (-3075 3850);
PAINT PEACH (-3075 3850);
DISPLAY INVISIBLE (-3075 3850);
FORCEPROP 2 LAST PATH I102
J 0
(-3450 4000);
DISPLAY 1.021277 (-3450 4000);
PAINT ORANGE (-3450 4000);
DISPLAY INVISIBLE (-3450 4000);
FORCEADD OFFPAGE..1
(-3200 3800);
FORCEPROP 2 LAST $XR0 111 
J 0
(-3482 3800);
DISPLAY 0.638298 (-3482 3800);
PAINT MONO (-3482 3800);
FORCEPROP 2 LAST $XR1 118 
J 0
(-3602 3800);
DISPLAY 0.638298 (-3602 3800);
PAINT MONO (-3602 3800);
FORCEPROP 2 LAST $XR2 112 
J 0
(-3722 3800);
DISPLAY 0.638298 (-3722 3800);
PAINT MONO (-3722 3800);
FORCEPROP 2 LAST CDS_LIB mstr_standard
J 0
(-3200 3800);
DISPLAY 2.212766 (-3200 3800);
PAINT ORANGE (-3200 3800);
DISPLAY INVISIBLE (-3200 3800);
FORCEPROP 1 LAST OFFPAGE TRUE
J 0
(-2875 3675);
DISPLAY 1.404255 (-2875 3675);
PAINT GREEN (-2875 3675);
DISPLAY INVISIBLE (-2875 3675);
FORCEPROP 1 LAST COMMENT_BODY TRUE
J 0
(-3075 3700);
DISPLAY 1.404255 (-3075 3700);
PAINT PEACH (-3075 3700);
DISPLAY INVISIBLE (-3075 3700);
FORCEPROP 2 LAST PATH I103
J 0
(-3450 3850);
DISPLAY 1.021277 (-3450 3850);
PAINT ORANGE (-3450 3850);
DISPLAY INVISIBLE (-3450 3850);
FORCEADD OFFPAGE..1
(-3200 3725);
FORCEPROP 2 LAST $XR0 111 
J 0
(-3482 3725);
DISPLAY 0.638298 (-3482 3725);
PAINT MONO (-3482 3725);
FORCEPROP 2 LAST $XR1 118 
J 0
(-3602 3725);
DISPLAY 0.638298 (-3602 3725);
PAINT MONO (-3602 3725);
FORCEPROP 2 LAST CDS_LIB mstr_standard
J 0
(-3200 3725);
DISPLAY 2.212766 (-3200 3725);
PAINT ORANGE (-3200 3725);
DISPLAY INVISIBLE (-3200 3725);
FORCEPROP 1 LAST OFFPAGE TRUE
J 0
(-2875 3600);
DISPLAY 1.404255 (-2875 3600);
PAINT GREEN (-2875 3600);
DISPLAY INVISIBLE (-2875 3600);
FORCEPROP 1 LAST COMMENT_BODY TRUE
J 0
(-3075 3625);
DISPLAY 1.404255 (-3075 3625);
PAINT PEACH (-3075 3625);
DISPLAY INVISIBLE (-3075 3625);
FORCEPROP 2 LAST PATH I104
J 0
(-3450 3775);
DISPLAY 1.021277 (-3450 3775);
PAINT ORANGE (-3450 3775);
DISPLAY INVISIBLE (-3450 3775);
FORCEADD OFFPAGE..1
(-3175 2775);
FORCEPROP 2 LAST $XR0 111 
J 0
(-3427 2775);
DISPLAY 0.638298 (-3427 2775);
PAINT MONO (-3427 2775);
FORCEPROP 2 LAST $XR1 118 
J 0
(-3547 2775);
DISPLAY 0.638298 (-3547 2775);
PAINT MONO (-3547 2775);
FORCEPROP 2 LAST $XR2 112 
J 0
(-3667 2775);
DISPLAY 0.638298 (-3667 2775);
PAINT MONO (-3667 2775);
FORCEPROP 2 LAST CDS_LIB mstr_standard
J 0
(-3175 2775);
PAINT ORANGE (-3175 2775);
DISPLAY INVISIBLE (-3175 2775);
FORCEPROP 1 LAST OFFPAGE TRUE
J 0
(-2850 2650);
DISPLAY 1.404255 (-2850 2650);
PAINT GREEN (-2850 2650);
DISPLAY INVISIBLE (-2850 2650);
FORCEPROP 1 LAST COMMENT_BODY TRUE
J 0
(-3050 2675);
DISPLAY 1.404255 (-3050 2675);
PAINT PEACH (-3050 2675);
DISPLAY INVISIBLE (-3050 2675);
FORCEPROP 2 LAST PATH I105
J 0
(-3425 2825);
DISPLAY 1.021277 (-3425 2825);
PAINT ORANGE (-3425 2825);
DISPLAY INVISIBLE (-3425 2825);
FORCEADD OFFPAGE..5
(-3175 2575);
FORCEPROP 2 LAST $XR0 118 
J 0
(-3430 2575);
DISPLAY 0.638298 (-3430 2575);
PAINT MONO (-3430 2575);
FORCEPROP 2 LAST $XR1 111 
J 0
(-3550 2575);
DISPLAY 0.638298 (-3550 2575);
PAINT MONO (-3550 2575);
FORCEPROP 2 LAST $XR2 112 
J 0
(-3670 2575);
DISPLAY 0.638298 (-3670 2575);
PAINT MONO (-3670 2575);
FORCEPROP 2 LAST BOM_COST DEBUG
J 2
(-3375 2675);
DISPLAY 1.617021 (-3375 2675);
PAINT WHITE (-3375 2675);
DISPLAY INVISIBLE (-3375 2675);
FORCEPROP 2 LAST ROOM CPU_JTAG_DEBUG
J 2
(-3375 2625);
DISPLAY 1.617021 (-3375 2625);
PAINT WHITE (-3375 2625);
DISPLAY INVISIBLE (-3375 2625);
FORCEPROP 2 LAST CDS_LIB mstr_standard
J 0
(-3175 2575);
PAINT ORANGE (-3175 2575);
DISPLAY INVISIBLE (-3175 2575);
FORCEPROP 1 LAST OFFPAGE TRUE
J 0
(-2850 2450);
DISPLAY 1.404255 (-2850 2450);
PAINT GREEN (-2850 2450);
DISPLAY INVISIBLE (-2850 2450);
FORCEPROP 1 LAST COMMENT_BODY TRUE
J 0
(-3075 2500);
DISPLAY 1.404255 (-3075 2500);
PAINT PEACH (-3075 2500);
DISPLAY INVISIBLE (-3075 2500);
FORCEPROP 2 LAST PATH I106
J 0
(-3450 2625);
DISPLAY 1.021277 (-3450 2625);
PAINT ORANGE (-3450 2625);
DISPLAY INVISIBLE (-3450 2625);
FORCEADD OFFPAGE..1
(-3175 2375);
FORCEPROP 2 LAST $XR0 111 
J 0
(-3427 2375);
DISPLAY 0.638298 (-3427 2375);
PAINT MONO (-3427 2375);
FORCEPROP 2 LAST $XR1 118 
J 0
(-3547 2375);
DISPLAY 0.638298 (-3547 2375);
PAINT MONO (-3547 2375);
FORCEPROP 2 LAST $XR2 112 
J 0
(-3667 2375);
DISPLAY 0.638298 (-3667 2375);
PAINT MONO (-3667 2375);
FORCEPROP 2 LAST CDS_LIB mstr_standard
J 0
(-3175 2375);
PAINT ORANGE (-3175 2375);
DISPLAY INVISIBLE (-3175 2375);
FORCEPROP 1 LAST OFFPAGE TRUE
J 0
(-2850 2250);
DISPLAY 1.404255 (-2850 2250);
PAINT GREEN (-2850 2250);
DISPLAY INVISIBLE (-2850 2250);
FORCEPROP 1 LAST COMMENT_BODY TRUE
J 0
(-3050 2275);
DISPLAY 1.404255 (-3050 2275);
PAINT PEACH (-3050 2275);
DISPLAY INVISIBLE (-3050 2275);
FORCEPROP 2 LAST PATH I107
J 0
(-3425 2425);
DISPLAY 1.021277 (-3425 2425);
PAINT ORANGE (-3425 2425);
DISPLAY INVISIBLE (-3425 2425);
FORCEADD TTL3126..3
(-2200 2425);
FORCEPROP 1 LAST POWER_GROUP VCC=P3V3_STBY;GND=GND
J 0
(-2350 1900);
DISPLAY 0.617021 (-2350 1900);
PAINT ORANGE (-2350 1900);
FORCEPROP 1 LAST LOCATION U1L1
J 0
(-2350 3000);
DISPLAY 0.617021 (-2350 3000);
PAINT AQUA (-2350 3000);
FORCEPROP 1 LAST PART_NUMBER D18317-001
J 0
(-2350 1950);
DISPLAY 0.617021 (-2350 1950);
PAINT BLUE (-2350 1950);
FORCEPROP 1 LAST VALUE 74CBTLV3126
J 0
(-2350 2900);
DISPLAY 0.617021 (-2350 2900);
PAINT SKYBLUE (-2350 2900);
FORCEPROP 1 LAST MATERIAL IC
J 0
(-2350 2950);
DISPLAY 0.617021 (-2350 2950);
PAINT SKYBLUE (-2350 2950);
FORCEPROP 2 LASTPIN (-2400 2075) $PN 1
J 2
(-2410 2085);
DISPLAY 0.617021 (-2410 2085);
PAINT WHITE (-2410 2085);
FORCEPROP 2 LASTPIN (-2400 2275) $PN 4
J 2
(-2410 2285);
DISPLAY 0.617021 (-2410 2285);
PAINT WHITE (-2410 2285);
FORCEPROP 2 LASTPIN (-2400 2475) $PN 10
J 2
(-2410 2485);
DISPLAY 0.617021 (-2410 2485);
PAINT WHITE (-2410 2485);
FORCEPROP 2 LASTPIN (-2400 2675) $PN 13
J 2
(-2410 2685);
DISPLAY 0.617021 (-2410 2685);
PAINT WHITE (-2410 2685);
FORCEPROP 2 LASTPIN (-2000 2175) $PN 3
J 0
(-1990 2185);
DISPLAY 0.617021 (-1990 2185);
PAINT WHITE (-1990 2185);
FORCEPROP 2 LASTPIN (-2000 2375) $PN 6
J 0
(-1990 2385);
DISPLAY 0.617021 (-1990 2385);
PAINT WHITE (-1990 2385);
FORCEPROP 2 LASTPIN (-2000 2575) $PN 8
J 0
(-1990 2585);
DISPLAY 0.617021 (-1990 2585);
PAINT WHITE (-1990 2585);
FORCEPROP 2 LASTPIN (-2000 2775) $PN 11
J 0
(-1990 2785);
DISPLAY 0.617021 (-1990 2785);
PAINT WHITE (-1990 2785);
FORCEPROP 2 LASTPIN (-2400 2175) $PN 2
J 2
(-2410 2185);
DISPLAY 0.617021 (-2410 2185);
PAINT WHITE (-2410 2185);
FORCEPROP 2 LASTPIN (-2400 2375) $PN 5
J 2
(-2410 2385);
DISPLAY 0.617021 (-2410 2385);
PAINT WHITE (-2410 2385);
FORCEPROP 2 LASTPIN (-2400 2575) $PN 9
J 2
(-2410 2585);
DISPLAY 0.617021 (-2410 2585);
PAINT WHITE (-2410 2585);
FORCEPROP 2 LASTPIN (-2400 2775) $PN 12
J 2
(-2410 2785);
DISPLAY 0.617021 (-2410 2785);
PAINT WHITE (-2410 2785);
FORCEPROP 1 LAST PACK_TYPE QFNLF
J 0
(-2350 3050);
DISPLAY 1.595745 (-2350 3050);
PAINT SKYBLUE (-2350 3050);
DISPLAY INVISIBLE (-2350 3050);
FORCEPROP 1 LAST HAS_FIXED_SIZE 4B
J 0
(-2350 1850);
DISPLAY 1.595745 (-2350 1850);
PAINT BLUE (-2350 1850);
DISPLAY INVISIBLE (-2350 1850);
FORCEPROP 2 LAST CDS_LIB mstr_ttl
J 0
(-2200 2425);
PAINT ORANGE (-2200 2425);
DISPLAY INVISIBLE (-2200 2425);
FORCEPROP 2 LAST CDS_LOCATION U1L1
J 0
(-2350 3000);
DISPLAY 0.617021 (-2350 3000);
PAINT AQUA (-2350 3000);
DISPLAY INVISIBLE (-2350 3000);
FORCEPROP 1 LAST PATH I108
J 0
(-1900 2950);
DISPLAY 0.978723 (-1900 2950);
PAINT BLUE (-1900 2950);
DISPLAY INVISIBLE (-1900 2950);
FORCEPROP 0 LAST ROOM DEBUG
J 0
(-2350 3100);
DISPLAY 1.021277 (-2350 3100);
PAINT ORANGE (-2350 3100);
DISPLAY INVISIBLE (-2350 3100);
FORCEADD TTL3126..3
(-2200 1200);
FORCEPROP 1 LAST POWER_GROUP VCC=P3V3_STBY;GND=GND
J 0
(-2350 675);
DISPLAY 0.617021 (-2350 675);
PAINT ORANGE (-2350 675);
FORCEPROP 1 LAST LOCATION U1L5
J 0
(-2350 1775);
DISPLAY 0.617021 (-2350 1775);
PAINT AQUA (-2350 1775);
FORCEPROP 1 LAST PART_NUMBER D18317-001
J 0
(-2350 725);
DISPLAY 0.617021 (-2350 725);
PAINT BLUE (-2350 725);
FORCEPROP 1 LAST VALUE 74CBTLV3126
J 0
(-2350 1675);
DISPLAY 0.617021 (-2350 1675);
PAINT SKYBLUE (-2350 1675);
FORCEPROP 1 LAST MATERIAL IC
J 0
(-2350 1725);
DISPLAY 0.617021 (-2350 1725);
PAINT SKYBLUE (-2350 1725);
FORCEPROP 2 LASTPIN (-2400 850) $PN 1
J 2
(-2410 860);
DISPLAY 0.617021 (-2410 860);
PAINT WHITE (-2410 860);
FORCEPROP 2 LASTPIN (-2400 1050) $PN 4
J 2
(-2410 1060);
DISPLAY 0.617021 (-2410 1060);
PAINT WHITE (-2410 1060);
FORCEPROP 2 LASTPIN (-2400 1250) $PN 10
J 2
(-2410 1260);
DISPLAY 0.617021 (-2410 1260);
PAINT WHITE (-2410 1260);
FORCEPROP 2 LASTPIN (-2400 1450) $PN 13
J 2
(-2410 1460);
DISPLAY 0.617021 (-2410 1460);
PAINT WHITE (-2410 1460);
FORCEPROP 2 LASTPIN (-2000 950) $PN 3
J 0
(-1990 960);
DISPLAY 0.617021 (-1990 960);
PAINT WHITE (-1990 960);
FORCEPROP 2 LASTPIN (-2000 1150) $PN 6
J 0
(-1990 1160);
DISPLAY 0.617021 (-1990 1160);
PAINT WHITE (-1990 1160);
FORCEPROP 2 LASTPIN (-2000 1350) $PN 8
J 0
(-1990 1360);
DISPLAY 0.617021 (-1990 1360);
PAINT WHITE (-1990 1360);
FORCEPROP 2 LASTPIN (-2000 1550) $PN 11
J 0
(-1990 1560);
DISPLAY 0.617021 (-1990 1560);
PAINT WHITE (-1990 1560);
FORCEPROP 2 LASTPIN (-2400 950) $PN 2
J 2
(-2410 960);
DISPLAY 0.617021 (-2410 960);
PAINT WHITE (-2410 960);
FORCEPROP 2 LASTPIN (-2400 1150) $PN 5
J 2
(-2410 1160);
DISPLAY 0.617021 (-2410 1160);
PAINT WHITE (-2410 1160);
FORCEPROP 2 LASTPIN (-2400 1350) $PN 9
J 2
(-2410 1360);
DISPLAY 0.617021 (-2410 1360);
PAINT WHITE (-2410 1360);
FORCEPROP 2 LASTPIN (-2400 1550) $PN 12
J 2
(-2410 1560);
DISPLAY 0.617021 (-2410 1560);
PAINT WHITE (-2410 1560);
FORCEPROP 1 LAST PACK_TYPE QFNLF
J 0
(-2350 1825);
DISPLAY 1.595745 (-2350 1825);
PAINT SKYBLUE (-2350 1825);
DISPLAY INVISIBLE (-2350 1825);
FORCEPROP 2 LAST CDS_LIB mstr_ttl
J 0
(-2200 1200);
PAINT ORANGE (-2200 1200);
DISPLAY INVISIBLE (-2200 1200);
FORCEPROP 1 LAST HAS_FIXED_SIZE 4B
J 0
(-2350 625);
DISPLAY 1.595745 (-2350 625);
PAINT BLUE (-2350 625);
DISPLAY INVISIBLE (-2350 625);
FORCEPROP 2 LAST CDS_LOCATION U1L5
J 0
(-2350 1775);
DISPLAY 0.617021 (-2350 1775);
PAINT AQUA (-2350 1775);
DISPLAY INVISIBLE (-2350 1775);
FORCEPROP 1 LAST PATH I109
J 0
(-1900 1725);
DISPLAY 0.978723 (-1900 1725);
PAINT BLUE (-1900 1725);
DISPLAY INVISIBLE (-1900 1725);
FORCEPROP 0 LAST ROOM DEBUG
J 0
(-2350 1875);
DISPLAY 1.021277 (-2350 1875);
PAINT ORANGE (-2350 1875);
DISPLAY INVISIBLE (-2350 1875);
FORCEADD OFFPAGE..1
(-3175 2175);
FORCEPROP 2 LAST $XR0 111 
J 0
(-3427 2175);
DISPLAY 0.638298 (-3427 2175);
PAINT MONO (-3427 2175);
FORCEPROP 2 LAST $XR1 118 
J 0
(-3547 2175);
DISPLAY 0.638298 (-3547 2175);
PAINT MONO (-3547 2175);
FORCEPROP 2 LAST $XR2 112 
J 0
(-3667 2175);
DISPLAY 0.638298 (-3667 2175);
PAINT MONO (-3667 2175);
FORCEPROP 2 LAST CDS_LIB mstr_standard
J 0
(-3175 2175);
PAINT ORANGE (-3175 2175);
DISPLAY INVISIBLE (-3175 2175);
FORCEPROP 1 LAST OFFPAGE TRUE
J 0
(-2850 2050);
DISPLAY 1.404255 (-2850 2050);
PAINT GREEN (-2850 2050);
DISPLAY INVISIBLE (-2850 2050);
FORCEPROP 1 LAST COMMENT_BODY TRUE
J 0
(-3050 2075);
DISPLAY 1.404255 (-3050 2075);
PAINT PEACH (-3050 2075);
DISPLAY INVISIBLE (-3050 2075);
FORCEPROP 2 LAST PATH I110
J 0
(-3425 2225);
DISPLAY 1.021277 (-3425 2225);
PAINT ORANGE (-3425 2225);
DISPLAY INVISIBLE (-3425 2225);
FORCEADD OFFPAGE..1
(-3175 1550);
FORCEPROP 2 LAST $XR0 111 
J 0
(-3427 1550);
DISPLAY 0.638298 (-3427 1550);
PAINT MONO (-3427 1550);
FORCEPROP 2 LAST $XR1 118 
J 0
(-3547 1550);
DISPLAY 0.638298 (-3547 1550);
PAINT MONO (-3547 1550);
FORCEPROP 2 LAST $XR2 112 
J 0
(-3667 1550);
DISPLAY 0.638298 (-3667 1550);
PAINT MONO (-3667 1550);
FORCEPROP 2 LAST CDS_LIB mstr_standard
J 0
(-3175 1550);
PAINT ORANGE (-3175 1550);
DISPLAY INVISIBLE (-3175 1550);
FORCEPROP 1 LAST OFFPAGE TRUE
J 0
(-2850 1425);
DISPLAY 1.404255 (-2850 1425);
PAINT GREEN (-2850 1425);
DISPLAY INVISIBLE (-2850 1425);
FORCEPROP 1 LAST COMMENT_BODY TRUE
J 0
(-3050 1450);
DISPLAY 1.404255 (-3050 1450);
PAINT PEACH (-3050 1450);
DISPLAY INVISIBLE (-3050 1450);
FORCEPROP 2 LAST PATH I111
J 0
(-3425 1600);
DISPLAY 1.021277 (-3425 1600);
PAINT ORANGE (-3425 1600);
DISPLAY INVISIBLE (-3425 1600);
FORCEADD OFFPAGE..5
(-3175 1350);
FORCEPROP 2 LAST $XR0 118 
J 0
(-3430 1350);
DISPLAY 0.638298 (-3430 1350);
PAINT MONO (-3430 1350);
FORCEPROP 2 LAST $XR1 111 
J 0
(-3550 1350);
DISPLAY 0.638298 (-3550 1350);
PAINT MONO (-3550 1350);
FORCEPROP 2 LAST $XR2 112 
J 0
(-3670 1350);
DISPLAY 0.638298 (-3670 1350);
PAINT MONO (-3670 1350);
FORCEPROP 2 LAST BOM_COST DEBUG
J 2
(-3375 1450);
DISPLAY 1.617021 (-3375 1450);
PAINT WHITE (-3375 1450);
DISPLAY INVISIBLE (-3375 1450);
FORCEPROP 2 LAST ROOM CPU_JTAG_DEBUG
J 2
(-3375 1400);
DISPLAY 1.617021 (-3375 1400);
PAINT WHITE (-3375 1400);
DISPLAY INVISIBLE (-3375 1400);
FORCEPROP 2 LAST CDS_LIB mstr_standard
J 0
(-3175 1350);
PAINT ORANGE (-3175 1350);
DISPLAY INVISIBLE (-3175 1350);
FORCEPROP 1 LAST OFFPAGE TRUE
J 0
(-2850 1225);
DISPLAY 1.404255 (-2850 1225);
PAINT GREEN (-2850 1225);
DISPLAY INVISIBLE (-2850 1225);
FORCEPROP 1 LAST COMMENT_BODY TRUE
J 0
(-3075 1275);
DISPLAY 1.404255 (-3075 1275);
PAINT PEACH (-3075 1275);
DISPLAY INVISIBLE (-3075 1275);
FORCEPROP 2 LAST PATH I112
J 0
(-3450 1400);
DISPLAY 1.021277 (-3450 1400);
PAINT ORANGE (-3450 1400);
DISPLAY INVISIBLE (-3450 1400);
FORCEADD OFFPAGE..1
(-3175 1150);
FORCEPROP 2 LAST $XR0 111 
J 0
(-3427 1150);
DISPLAY 0.638298 (-3427 1150);
PAINT MONO (-3427 1150);
FORCEPROP 2 LAST CDS_LIB mstr_standard
J 0
(-3175 1150);
PAINT ORANGE (-3175 1150);
DISPLAY INVISIBLE (-3175 1150);
FORCEPROP 1 LAST OFFPAGE TRUE
J 0
(-2850 1025);
DISPLAY 1.404255 (-2850 1025);
PAINT GREEN (-2850 1025);
DISPLAY INVISIBLE (-2850 1025);
FORCEPROP 1 LAST COMMENT_BODY TRUE
J 0
(-3050 1050);
DISPLAY 1.404255 (-3050 1050);
PAINT PEACH (-3050 1050);
DISPLAY INVISIBLE (-3050 1050);
FORCEPROP 2 LAST PATH I113
J 0
(-3425 1200);
DISPLAY 1.021277 (-3425 1200);
PAINT ORANGE (-3425 1200);
DISPLAY INVISIBLE (-3425 1200);
FORCEADD OFFPAGE..1
(-3175 950);
FORCEPROP 2 LAST $XR0 111 
J 0
(-3427 950);
DISPLAY 0.638298 (-3427 950);
PAINT MONO (-3427 950);
FORCEPROP 2 LAST CDS_LIB mstr_standard
J 0
(-3175 950);
PAINT ORANGE (-3175 950);
DISPLAY INVISIBLE (-3175 950);
FORCEPROP 1 LAST OFFPAGE TRUE
J 0
(-2850 825);
DISPLAY 1.404255 (-2850 825);
PAINT GREEN (-2850 825);
DISPLAY INVISIBLE (-2850 825);
FORCEPROP 1 LAST COMMENT_BODY TRUE
J 0
(-3050 850);
DISPLAY 1.404255 (-3050 850);
PAINT PEACH (-3050 850);
DISPLAY INVISIBLE (-3050 850);
FORCEPROP 2 LAST PATH I114
J 0
(-3425 1000);
DISPLAY 1.021277 (-3425 1000);
PAINT ORANGE (-3425 1000);
DISPLAY INVISIBLE (-3425 1000);
FORCEADD OFFPAGE..1
(-3175 850);
FORCEPROP 2 LAST $XR0 201 
J 0
(-3427 850);
DISPLAY 0.638298 (-3427 850);
PAINT MONO (-3427 850);
FORCEPROP 2 LAST $XR1 190 
J 0
(-3547 850);
DISPLAY 0.638298 (-3547 850);
PAINT MONO (-3547 850);
FORCEPROP 2 LAST CDS_LIB mstr_standard
J 0
(-3175 850);
PAINT ORANGE (-3175 850);
DISPLAY INVISIBLE (-3175 850);
FORCEPROP 1 LAST OFFPAGE TRUE
J 0
(-2850 725);
DISPLAY 1.404255 (-2850 725);
PAINT GREEN (-2850 725);
DISPLAY INVISIBLE (-2850 725);
FORCEPROP 1 LAST COMMENT_BODY TRUE
J 0
(-3050 750);
DISPLAY 1.404255 (-3050 750);
PAINT PEACH (-3050 750);
DISPLAY INVISIBLE (-3050 750);
FORCEPROP 2 LAST PATH I115
J 0
(-3125 925);
DISPLAY 1.021277 (-3125 925);
PAINT ORANGE (-3125 925);
DISPLAY INVISIBLE (-3125 925);
FORCEADD RES..2
(3500 2400);
FORCEPROP 1 LAST LOCATION R6T9
J 0
(3545 2525);
DISPLAY 0.617021 (3545 2525);
PAINT AQUA (3545 2525);
FORCEPROP 1 LAST PART_NUMBER G21796-017
J 0
(3540 2275);
DISPLAY 0.617021 (3540 2275);
PAINT BLUE (3540 2275);
FORCEPROP 1 LAST VALUE 100.0
J 0
(3545 2475);
DISPLAY 0.617021 (3545 2475);
PAINT SKYBLUE (3545 2475);
FORCEPROP 1 LAST TOLERANCE 1%
J 0
(3545 2425);
DISPLAY 0.617021 (3545 2425);
PAINT SKYBLUE (3545 2425);
FORCEPROP 1 LAST PACK_TYPE 0402
J 0
(3540 2225);
DISPLAY 0.617021 (3540 2225);
PAINT SKYBLUE (3540 2225);
FORCEPROP 1 LAST MATERIAL CHIP
J 0
(3540 2325);
DISPLAY 0.617021 (3540 2325);
PAINT SKYBLUE (3540 2325);
FORCEPROP 1 LAST WATTAGE 1/16W
J 0
(3540 2375);
DISPLAY 0.617021 (3540 2375);
PAINT SKYBLUE (3540 2375);
FORCEPROP 1 LASTPIN (3500 2300) $PN 2
J 0
(3505 2310);
DISPLAY 0.617021 (3505 2310);
PAINT ORANGE (3505 2310);
FORCEPROP 1 LASTPIN (3500 2500) $PN 1
J 0
(3505 2462);
DISPLAY 0.617021 (3505 2462);
PAINT ORANGE (3505 2462);
FORCEPROP 2 LAST SEC_TYPE 0402
J 0
(3550 2625);
DISPLAY 1.021277 (3550 2625);
PAINT ORANGE (3550 2625);
DISPLAY INVISIBLE (3550 2625);
FORCEPROP 2 LAST CDS_LIB mstr_discrete
J 0
(3500 2400);
PAINT ORANGE (3500 2400);
DISPLAY INVISIBLE (3500 2400);
FORCEPROP 2 LAST SEC 1
J 0
(3550 2625);
DISPLAY 0.680851 (3550 2625);
PAINT MONO (3550 2625);
DISPLAY INVISIBLE (3550 2625);
FORCEPROP 2 LAST CDS_LOCATION R6T9
J 0
(3545 2525);
DISPLAY 0.617021 (3545 2525);
PAINT AQUA (3545 2525);
DISPLAY INVISIBLE (3545 2525);
FORCEPROP 1 LAST PATH I120
J 0
(3550 2575);
DISPLAY 0.978723 (3550 2575);
PAINT WHITE (3550 2575);
DISPLAY INVISIBLE (3550 2575);
FORCEPROP 2 LAST ROOM DEBUG
J 0
(3545 2565);
DISPLAY 1.276596 (3545 2565);
PAINT WHITE (3545 2565);
DISPLAY INVISIBLE (3545 2565);
FORCEADD RES..2
(3175 2400);
FORCEPROP 1 LAST LOCATION R6T8
J 0
(3220 2525);
DISPLAY 0.617021 (3220 2525);
PAINT AQUA (3220 2525);
FORCEPROP 1 LAST PART_NUMBER G21796-017
J 0
(3215 2275);
DISPLAY 0.617021 (3215 2275);
PAINT BLUE (3215 2275);
FORCEPROP 1 LAST VALUE 100.0
J 0
(3220 2475);
DISPLAY 0.617021 (3220 2475);
PAINT SKYBLUE (3220 2475);
FORCEPROP 1 LAST TOLERANCE 1%
J 0
(3220 2425);
DISPLAY 0.617021 (3220 2425);
PAINT SKYBLUE (3220 2425);
FORCEPROP 1 LAST PACK_TYPE 0402
J 0
(3215 2225);
DISPLAY 0.617021 (3215 2225);
PAINT SKYBLUE (3215 2225);
FORCEPROP 1 LAST MATERIAL CHIP
J 0
(3215 2325);
DISPLAY 0.617021 (3215 2325);
PAINT SKYBLUE (3215 2325);
FORCEPROP 1 LAST WATTAGE 1/16W
J 0
(3215 2375);
DISPLAY 0.617021 (3215 2375);
PAINT SKYBLUE (3215 2375);
FORCEPROP 1 LASTPIN (3175 2300) $PN 2
J 0
(3180 2310);
DISPLAY 0.617021 (3180 2310);
PAINT ORANGE (3180 2310);
FORCEPROP 1 LASTPIN (3175 2500) $PN 1
J 0
(3180 2462);
DISPLAY 0.617021 (3180 2462);
PAINT ORANGE (3180 2462);
FORCEPROP 2 LAST SEC_TYPE 0402
J 0
(3225 2625);
DISPLAY 1.021277 (3225 2625);
PAINT ORANGE (3225 2625);
DISPLAY INVISIBLE (3225 2625);
FORCEPROP 2 LAST CDS_LIB mstr_discrete
J 0
(3175 2400);
PAINT ORANGE (3175 2400);
DISPLAY INVISIBLE (3175 2400);
FORCEPROP 2 LAST SEC 1
J 0
(3225 2625);
DISPLAY 0.680851 (3225 2625);
PAINT MONO (3225 2625);
DISPLAY INVISIBLE (3225 2625);
FORCEPROP 2 LAST CDS_LOCATION R6T8
J 0
(3220 2525);
DISPLAY 0.617021 (3220 2525);
PAINT AQUA (3220 2525);
DISPLAY INVISIBLE (3220 2525);
FORCEPROP 1 LAST PATH I121
J 0
(3225 2575);
DISPLAY 0.978723 (3225 2575);
PAINT WHITE (3225 2575);
DISPLAY INVISIBLE (3225 2575);
FORCEPROP 2 LAST ROOM DEBUG
J 0
(3220 2565);
DISPLAY 1.276596 (3220 2565);
PAINT WHITE (3220 2565);
DISPLAY INVISIBLE (3220 2565);
FORCEADD PVCCIO_CPU0..1
(3500 2700);
FORCEPROP 3 LASTPIN (3500 2650) SIG_NAME PVCCIO_CPU0\g
J 0
(3510 2660);
DISPLAY 0.659574 (3510 2660);
PAINT MONO (3510 2660);
DISPLAY INVISIBLE (3510 2660);
FORCEPROP 1 LAST VOLTAGE 1.1V
J 0
(3455 2657);
DISPLAY 0.340426 (3455 2657);
PAINT SKYBLUE (3455 2657);
DISPLAY INVISIBLE (3455 2657);
FORCEPROP 2 LAST CDS_LIB mstr_symbols
J 0
(3500 2700);
PAINT ORANGE (3500 2700);
DISPLAY INVISIBLE (3500 2700);
FORCEPROP 1 LAST BODY_TYPE PLUMBING
J 0
(3455 2657);
DISPLAY 0.340426 (3455 2657);
PAINT GREEN (3455 2657);
DISPLAY INVISIBLE (3455 2657);
FORCEPROP 1 LAST PATH I122
J 0
(3550 2725);
DISPLAY 0.872340 (3550 2725);
PAINT AQUA (3550 2725);
DISPLAY INVISIBLE (3550 2725);
FORCEPROP 1 LAST HDL_POWER PVCCIO_CPU0
J 1
(3500 2750);
DISPLAY 0.872340 (3500 2750);
PAINT GREEN (3500 2750);
DISPLAY INVISIBLE (3500 2750);
FORCEADD PVCCIO_CPU0..1
(1950 2725);
FORCEPROP 3 LASTPIN (1950 2675) SIG_NAME PVCCIO_CPU0\g
J 0
(1960 2685);
DISPLAY 0.659574 (1960 2685);
PAINT MONO (1960 2685);
DISPLAY INVISIBLE (1960 2685);
FORCEPROP 1 LAST VOLTAGE 1.1V
J 0
(1905 2682);
DISPLAY 0.340426 (1905 2682);
PAINT SKYBLUE (1905 2682);
DISPLAY INVISIBLE (1905 2682);
FORCEPROP 2 LAST CDS_LIB mstr_symbols
J 0
(1950 2725);
PAINT ORANGE (1950 2725);
DISPLAY INVISIBLE (1950 2725);
FORCEPROP 1 LAST BODY_TYPE PLUMBING
J 0
(1905 2682);
DISPLAY 0.340426 (1905 2682);
PAINT GREEN (1905 2682);
DISPLAY INVISIBLE (1905 2682);
FORCEPROP 1 LAST PATH I123
J 0
(2000 2750);
DISPLAY 0.872340 (2000 2750);
PAINT AQUA (2000 2750);
DISPLAY INVISIBLE (2000 2750);
FORCEPROP 1 LAST HDL_POWER PVCCIO_CPU0
J 1
(1950 2775);
DISPLAY 0.872340 (1950 2775);
PAINT GREEN (1950 2775);
DISPLAY INVISIBLE (1950 2775);
FORCEADD P1V05_PCH_STBY..1
(-1200 4750);
FORCEPROP 3 LASTPIN (-1200 4700) SIG_NAME P1V05_PCH_STBY\g
J 0
(-1190 4710);
DISPLAY 0.659574 (-1190 4710);
PAINT MONO (-1190 4710);
DISPLAY INVISIBLE (-1190 4710);
FORCEPROP 1 LAST VOLTAGE 1.05V
J 0
(-1245 4707);
DISPLAY 0.340426 (-1245 4707);
PAINT SKYBLUE (-1245 4707);
DISPLAY INVISIBLE (-1245 4707);
FORCEPROP 2 LAST CDS_LIB mstr_symbols
J 0
(-1200 4750);
PAINT ORANGE (-1200 4750);
DISPLAY INVISIBLE (-1200 4750);
FORCEPROP 1 LAST BODY_TYPE PLUMBING
J 0
(-1245 4707);
DISPLAY 0.340426 (-1245 4707);
PAINT GREEN (-1245 4707);
DISPLAY INVISIBLE (-1245 4707);
FORCEPROP 1 LAST PATH I126
J 0
(-1150 4775);
DISPLAY 0.872340 (-1150 4775);
PAINT AQUA (-1150 4775);
DISPLAY INVISIBLE (-1150 4775);
FORCEPROP 1 LAST HDL_POWER P1V05_PCH_STBY
J 0
(-1200 4800);
DISPLAY 0.872340 (-1200 4800);
PAINT GREEN (-1200 4800);
DISPLAY INVISIBLE (-1200 4800);
FORCEADD 74CBTLV1G125..1
(3075 3425);
FORCEPROP 1 LAST POWER_GROUP VCC=P3V3_STBY;GND=GND;
J 0
(2850 3225);
DISPLAY 0.617021 (2850 3225);
PAINT ORANGE (2850 3225);
FORCEPROP 1 LAST LOCATION U1M4
J 0
(2909 3556);
DISPLAY 0.617021 (2909 3556);
PAINT AQUA (2909 3556);
FORCEPROP 1 LAST PART_NUMBER C88177-001
J 0
(2910 3285);
DISPLAY 0.617021 (2910 3285);
PAINT BLUE (2910 3285);
FORCEPROP 1 LAST PACK_TYPE SMLF
J 0
(2900 3595);
DISPLAY 0.617021 (2900 3595);
PAINT SKYBLUE (2900 3595);
FORCEPROP 1 LAST MATERIAL IC
J 0
(2900 3645);
DISPLAY 0.617021 (2900 3645);
PAINT SKYBLUE (2900 3645);
FORCEPROP 2 LASTPIN (2825 3375) $PN 1
J 2
(2815 3385);
DISPLAY 0.617021 (2815 3385);
PAINT ORANGE (2815 3385);
FORCEPROP 2 LASTPIN (3325 3425) $PN 4
J 0
(3335 3435);
DISPLAY 0.617021 (3335 3435);
PAINT ORANGE (3335 3435);
FORCEPROP 2 LASTPIN (2825 3425) $PN 2
J 2
(2815 3435);
DISPLAY 0.617021 (2815 3435);
PAINT ORANGE (2815 3435);
FORCEPROP 2 LAST SEC_TYPE SMLF
J 0
(2900 3700);
DISPLAY 1.021277 (2900 3700);
PAINT ORANGE (2900 3700);
DISPLAY INVISIBLE (2900 3700);
FORCEPROP 2 LAST CDS_LIB mstr_ttl
J 0
(3075 3425);
PAINT ORANGE (3075 3425);
DISPLAY INVISIBLE (3075 3425);
FORCEPROP 0 LAST BOM_COST DEBUG
J 0
(2900 3750);
DISPLAY 1.021277 (2900 3750);
PAINT ORANGE (2900 3750);
DISPLAY INVISIBLE (2900 3750);
FORCEPROP 2 LAST SEC 1
J 0
(2900 3700);
DISPLAY 0.680851 (2900 3700);
PAINT MONO (2900 3700);
DISPLAY INVISIBLE (2900 3700);
FORCEPROP 1 LAST PATH I127
J 0
(3175 3545);
DISPLAY 0.872340 (3175 3545);
PAINT PINK (3175 3545);
DISPLAY INVISIBLE (3175 3545);
FORCEPROP 0 LAST ROOM DEBUG
J 0
(2900 3750);
DISPLAY 1.021277 (2900 3750);
PAINT ORANGE (2900 3750);
DISPLAY INVISIBLE (2900 3750);
FORCEADD OFFPAGE..1
(2150 3425);
FORCEPROP 2 LAST $XR0 21 
J 0
(1899 3425);
DISPLAY 0.638298 (1899 3425);
PAINT MONO (1899 3425);
FORCEPROP 2 LAST $XR1 112 
J 0
(1779 3425);
DISPLAY 0.638298 (1779 3425);
PAINT MONO (1779 3425);
FORCEPROP 2 LAST CDS_LIB mstr_standard
J 0
(2150 3425);
PAINT ORANGE (2150 3425);
DISPLAY INVISIBLE (2150 3425);
FORCEPROP 1 LAST OFFPAGE TRUE
J 0
(2475 3300);
DISPLAY 1.404255 (2475 3300);
PAINT GREEN (2475 3300);
DISPLAY INVISIBLE (2475 3300);
FORCEPROP 1 LAST COMMENT_BODY TRUE
J 0
(2275 3325);
DISPLAY 1.404255 (2275 3325);
PAINT PEACH (2275 3325);
DISPLAY INVISIBLE (2275 3325);
FORCEPROP 2 LAST PATH I128
J 0
(2200 3500);
DISPLAY 1.021277 (2200 3500);
PAINT ORANGE (2200 3500);
DISPLAY INVISIBLE (2200 3500);
FORCEADD OFFPAGE..1
(2150 3375);
FORCEPROP 2 LAST $XR0 55 
J 0
(1899 3375);
DISPLAY 0.638298 (1899 3375);
PAINT MONO (1899 3375);
FORCEPROP 2 LAST $XR1 112 
J 0
(1779 3375);
DISPLAY 0.638298 (1779 3375);
PAINT MONO (1779 3375);
FORCEPROP 2 LAST $XR2 118 
J 0
(1659 3375);
DISPLAY 0.638298 (1659 3375);
PAINT MONO (1659 3375);
FORCEPROP 2 LAST $XR3 144 
J 0
(1779 3339);
DISPLAY 0.638298 (1779 3339);
PAINT MONO (1779 3339);
FORCEPROP 2 LAST $XR4 190 
J 0
(1659 3339);
DISPLAY 0.638298 (1659 3339);
PAINT MONO (1659 3339);
FORCEPROP 2 LAST CDS_LIB mstr_standard
J 0
(2150 3375);
PAINT ORANGE (2150 3375);
DISPLAY INVISIBLE (2150 3375);
FORCEPROP 1 LAST OFFPAGE TRUE
J 0
(2475 3250);
DISPLAY 1.404255 (2475 3250);
PAINT GREEN (2475 3250);
DISPLAY INVISIBLE (2475 3250);
FORCEPROP 1 LAST COMMENT_BODY TRUE
J 0
(2275 3275);
DISPLAY 1.404255 (2275 3275);
PAINT PEACH (2275 3275);
DISPLAY INVISIBLE (2275 3275);
FORCEPROP 2 LAST PATH I129
J 0
(2200 3450);
DISPLAY 1.021277 (2200 3450);
PAINT ORANGE (2200 3450);
DISPLAY INVISIBLE (2200 3450);
FORCEADD OFFPAGE..5
R 2
(3775 3425);
FORCEPROP 2 LAST $XR0 55 
J 0
(3964 3425);
DISPLAY 0.638298 (3964 3425);
PAINT MONO (3964 3425);
FORCEPROP 2 LAST $XR1 112 
J 0
(4054 3425);
DISPLAY 0.638298 (4054 3425);
PAINT MONO (4054 3425);
FORCEPROP 2 LAST ROOM CPU_JTAG_DEBUG
J 2
(4025 3475);
DISPLAY 1.617021 (4025 3475);
PAINT WHITE (4025 3475);
DISPLAY INVISIBLE (4025 3475);
FORCEPROP 2 LAST BOM_COST DEBUG
J 2
(4025 3525);
DISPLAY 1.617021 (4025 3525);
PAINT WHITE (4025 3525);
DISPLAY INVISIBLE (4025 3525);
FORCEPROP 2 LAST CDS_LIB mstr_standard
J 0
(3775 3425);
PAINT ORANGE (3775 3425);
DISPLAY INVISIBLE (3775 3425);
FORCEPROP 1 LAST OFFPAGE TRUE
J 2
(3450 3300);
DISPLAY 1.404255 (3450 3300);
PAINT GREEN (3450 3300);
DISPLAY INVISIBLE (3450 3300);
FORCEPROP 1 LAST COMMENT_BODY TRUE
J 2
(3675 3350);
DISPLAY 1.404255 (3675 3350);
PAINT PEACH (3675 3350);
DISPLAY INVISIBLE (3675 3350);
FORCEPROP 2 LAST PATH I130
J 0
(3950 3500);
DISPLAY 1.021277 (3950 3500);
PAINT ORANGE (3950 3500);
DISPLAY INVISIBLE (3950 3500);
FORCEADD CAP_A..1
R 2
(3550 3725);
FORCEPROP 1 LAST LOCATION C1M30
J 2
(3500 3825);
DISPLAY 0.617021 (3500 3825);
PAINT AQUA (3500 3825);
FORCEPROP 1 LAST PART_NUMBER A36096-045
J 2
(3500 3575);
DISPLAY 0.617021 (3500 3575);
PAINT BLUE (3500 3575);
FORCEPROP 1 LAST VALUE 0.01UF
J 2
(3500 3775);
DISPLAY 0.617021 (3500 3775);
PAINT SKYBLUE (3500 3775);
FORCEPROP 1 LAST TOLERANCE 10%
J 2
(3500 3675);
DISPLAY 0.617021 (3500 3675);
PAINT SKYBLUE (3500 3675);
FORCEPROP 1 LAST PACK_TYPE 0402V
J 2
(3500 3525);
DISPLAY 0.617021 (3500 3525);
PAINT SKYBLUE (3500 3525);
FORCEPROP 1 LAST VOLTAGE 25V
J 2
(3500 3725);
DISPLAY 0.617021 (3500 3725);
PAINT SKYBLUE (3500 3725);
FORCEPROP 1 LAST MATERIAL X7R
J 2
(3500 3625);
DISPLAY 0.617021 (3500 3625);
PAINT SKYBLUE (3500 3625);
FORCEPROP 1 LASTPIN (3550 3825) $PN 1
J 2
(3540 3805);
DISPLAY 0.617021 (3540 3805);
PAINT ORANGE (3540 3805);
FORCEPROP 1 LASTPIN (3550 3625) $PN 2
J 2
(3540 3605);
DISPLAY 0.617021 (3540 3605);
PAINT ORANGE (3540 3605);
FORCEPROP 2 LAST BOM_COST DEBUG
J 0
(3500 3875);
DISPLAY 1.617021 (3500 3875);
PAINT WHITE (3500 3875);
DISPLAY INVISIBLE (3500 3875);
FORCEPROP 2 LAST CDS_LIB dev_discrete
J 0
(3550 3725);
PAINT ORANGE (3550 3725);
DISPLAY INVISIBLE (3550 3725);
FORCEPROP 2 LAST CDS_SEC 1
J 0
(3500 3875);
PAINT ORANGE (3500 3875);
DISPLAY INVISIBLE (3500 3875);
FORCEPROP 2 LAST SEC_TYPE 0402V
J 0
(3500 3925);
DISPLAY 1.021277 (3500 3925);
PAINT ORANGE (3500 3925);
DISPLAY INVISIBLE (3500 3925);
FORCEPROP 2 LAST SEC 1
J 0
(3500 3925);
DISPLAY 0.680851 (3500 3925);
PAINT MONO (3500 3925);
DISPLAY INVISIBLE (3500 3925);
FORCEPROP 1 LAST PATH I131
J 2
(3500 3875);
DISPLAY 0.978723 (3500 3875);
PAINT WHITE (3500 3875);
DISPLAY INVISIBLE (3500 3875);
FORCEPROP 2 LAST ROOM DEBUG
J 2
(3500 3875);
DISPLAY 1.617021 (3500 3875);
PAINT WHITE (3500 3875);
DISPLAY INVISIBLE (3500 3875);
FORCEADD GND..1
(3550 3525);
FORCEPROP 3 LASTPIN (3550 3575) SIG_NAME GND\g
J 0
(3560 3585);
DISPLAY 0.659574 (3560 3585);
PAINT MONO (3560 3585);
DISPLAY INVISIBLE (3560 3585);
FORCEPROP 1 LAST VOLTAGE 0.0V
J 0
(3505 3482);
DISPLAY 0.340426 (3505 3482);
PAINT SKYBLUE (3505 3482);
DISPLAY INVISIBLE (3505 3482);
FORCEPROP 1 LAST SIZE 1B
J 0
(3625 3475);
DISPLAY 1.893617 (3625 3475);
PAINT GREEN (3625 3475);
DISPLAY INVISIBLE (3625 3475);
FORCEPROP 2 LAST BOM_COST DEBUG
J 0
(3075 3650);
DISPLAY 1.617021 (3075 3650);
PAINT WHITE (3075 3650);
DISPLAY INVISIBLE (3075 3650);
FORCEPROP 2 LAST CDS_LIB mstr_symbols
J 0
(3550 3525);
PAINT ORANGE (3550 3525);
DISPLAY INVISIBLE (3550 3525);
FORCEPROP 1 LAST BODY_TYPE PLUMBING
J 0
(3505 3482);
DISPLAY 0.340426 (3505 3482);
PAINT GREEN (3505 3482);
DISPLAY INVISIBLE (3505 3482);
FORCEPROP 1 LAST PATH I133
J 0
(3625 3525);
DISPLAY 0.872340 (3625 3525);
PAINT AQUA (3625 3525);
DISPLAY INVISIBLE (3625 3525);
FORCEPROP 2 LAST ROOM CPU_JTAG_DEBUG
J 0
(3075 3600);
DISPLAY 1.617021 (3075 3600);
PAINT WHITE (3075 3600);
DISPLAY INVISIBLE (3075 3600);
FORCEPROP 1 LAST HDL_POWER GND
J 0
(3550 3675);
PAINT GREEN (3550 3675);
DISPLAY INVISIBLE (3550 3675);
FORCEADD PVCCIO_CPU0..1
(500 2675);
FORCEPROP 3 LASTPIN (500 2625) SIG_NAME PVCCIO_CPU0\g
J 0
(510 2635);
DISPLAY 0.659574 (510 2635);
PAINT MONO (510 2635);
DISPLAY INVISIBLE (510 2635);
FORCEPROP 1 LAST VOLTAGE 1.1V
J 0
(455 2632);
DISPLAY 0.340426 (455 2632);
PAINT SKYBLUE (455 2632);
DISPLAY INVISIBLE (455 2632);
FORCEPROP 2 LAST CDS_LIB mstr_symbols
J 0
(500 2675);
PAINT ORANGE (500 2675);
DISPLAY INVISIBLE (500 2675);
FORCEPROP 1 LAST BODY_TYPE PLUMBING
J 0
(455 2632);
DISPLAY 0.340426 (455 2632);
PAINT GREEN (455 2632);
DISPLAY INVISIBLE (455 2632);
FORCEPROP 1 LAST PATH I134
J 0
(550 2700);
DISPLAY 0.872340 (550 2700);
PAINT AQUA (550 2700);
DISPLAY INVISIBLE (550 2700);
FORCEPROP 1 LAST HDL_POWER PVCCIO_CPU0
J 1
(500 2725);
DISPLAY 0.872340 (500 2725);
PAINT GREEN (500 2725);
DISPLAY INVISIBLE (500 2725);
FORCEADD PVCCIO_CPU1..1
(1225 2675);
FORCEPROP 3 LASTPIN (1225 2625) SIG_NAME PVCCIO_CPU1\g
J 0
(1235 2635);
DISPLAY 0.659574 (1235 2635);
PAINT MONO (1235 2635);
DISPLAY INVISIBLE (1235 2635);
FORCEPROP 1 LAST VOLTAGE 1.1V
J 0
(1180 2632);
DISPLAY 0.340426 (1180 2632);
PAINT SKYBLUE (1180 2632);
DISPLAY INVISIBLE (1180 2632);
FORCEPROP 2 LAST CDS_LIB mstr_symbols
J 0
(1225 2675);
PAINT ORANGE (1225 2675);
DISPLAY INVISIBLE (1225 2675);
FORCEPROP 1 LAST BODY_TYPE PLUMBING
J 0
(1180 2632);
DISPLAY 0.340426 (1180 2632);
PAINT GREEN (1180 2632);
DISPLAY INVISIBLE (1180 2632);
FORCEPROP 1 LAST PATH I135
J 0
(1275 2700);
DISPLAY 0.872340 (1275 2700);
PAINT AQUA (1275 2700);
DISPLAY INVISIBLE (1275 2700);
FORCEPROP 1 LAST HDL_POWER PVCCIO_CPU1
J 1
(1225 2725);
DISPLAY 0.872340 (1225 2725);
PAINT GREEN (1225 2725);
DISPLAY INVISIBLE (1225 2725);
FORCEADD CAP..1
(-1125 1850);
FORCEPROP 1 LAST LOCATION C1L1
J 0
(-1075 1950);
DISPLAY 0.617021 (-1075 1950);
PAINT AQUA (-1075 1950);
FORCEPROP 1 LAST PART_NUMBER D97712-011
J 0
(-1075 1700);
DISPLAY 0.617021 (-1075 1700);
PAINT BLUE (-1075 1700);
FORCEPROP 1 LAST VALUE 1.0UF
J 0
(-1075 1900);
DISPLAY 0.617021 (-1075 1900);
PAINT SKYBLUE (-1075 1900);
FORCEPROP 1 LAST TOLERANCE 10%
J 0
(-1075 1800);
DISPLAY 0.617021 (-1075 1800);
PAINT SKYBLUE (-1075 1800);
FORCEPROP 1 LAST PACK_TYPE 0402
J 0
(-1075 1650);
DISPLAY 0.617021 (-1075 1650);
PAINT SKYBLUE (-1075 1650);
FORCEPROP 1 LAST VOLTAGE 16V
J 0
(-1075 1850);
DISPLAY 0.617021 (-1075 1850);
PAINT SKYBLUE (-1075 1850);
FORCEPROP 1 LAST MATERIAL X6S
J 0
(-1075 1750);
DISPLAY 0.617021 (-1075 1750);
PAINT SKYBLUE (-1075 1750);
FORCEPROP 1 LASTPIN (-1125 1750) $PN 2
J 0
(-1115 1730);
DISPLAY 0.617021 (-1115 1730);
PAINT ORANGE (-1115 1730);
FORCEPROP 1 LASTPIN (-1125 1950) $PN 1
J 0
(-1115 1930);
DISPLAY 0.617021 (-1115 1930);
PAINT ORANGE (-1115 1930);
FORCEPROP 2 LAST CDS_LIB mstr_discrete
J 0
(-1125 1850);
PAINT MONO (-1125 1850);
DISPLAY INVISIBLE (-1125 1850);
FORCEPROP 2 LAST SEC_TYPE 0402
J 0
(-1075 2050);
DISPLAY 1.021277 (-1075 2050);
PAINT ORANGE (-1075 2050);
DISPLAY INVISIBLE (-1075 2050);
FORCEPROP 2 LAST SEC 1
J 0
(-1075 2050);
DISPLAY 0.680851 (-1075 2050);
PAINT MONO (-1075 2050);
DISPLAY INVISIBLE (-1075 2050);
FORCEPROP 2 LAST CDS_LOCATION C1L1
J 0
(-1075 1950);
DISPLAY 0.617021 (-1075 1950);
PAINT AQUA (-1075 1950);
DISPLAY INVISIBLE (-1075 1950);
FORCEPROP 1 LAST PATH I136
J 0
(-1075 2000);
DISPLAY 0.978723 (-1075 2000);
PAINT WHITE (-1075 2000);
DISPLAY INVISIBLE (-1075 2000);
FORCEPROP 0 LAST ROOM DEBUG
J 0
(-1075 2050);
DISPLAY 1.021277 (-1075 2050);
PAINT ORANGE (-1075 2050);
DISPLAY INVISIBLE (-1075 2050);
FORCEADD GND..1
(-1125 1675);
FORCEPROP 3 LASTPIN (-1125 1725) SIG_NAME GND\g
J 0
(-1115 1735);
DISPLAY 0.659574 (-1115 1735);
PAINT MONO (-1115 1735);
DISPLAY INVISIBLE (-1115 1735);
FORCEPROP 1 LAST VOLTAGE 0.0V
J 0
(-1170 1632);
DISPLAY 0.340426 (-1170 1632);
PAINT SKYBLUE (-1170 1632);
DISPLAY INVISIBLE (-1170 1632);
FORCEPROP 2 LAST CDS_LIB mstr_symbols
J 0
(-1125 1675);
PAINT MONO (-1125 1675);
DISPLAY INVISIBLE (-1125 1675);
FORCEPROP 1 LAST SIZE 1B
J 0
(-1050 1625);
DISPLAY 2.382979 (-1050 1625);
PAINT GREEN (-1050 1625);
DISPLAY INVISIBLE (-1050 1625);
FORCEPROP 1 LAST BODY_TYPE PLUMBING
J 0
(-1170 1632);
DISPLAY 0.340426 (-1170 1632);
PAINT GREEN (-1170 1632);
DISPLAY INVISIBLE (-1170 1632);
FORCEPROP 1 LAST PATH I138
J 0
(-1050 1675);
DISPLAY 0.872340 (-1050 1675);
PAINT AQUA (-1050 1675);
DISPLAY INVISIBLE (-1050 1675);
FORCEPROP 1 LAST HDL_POWER GND
J 0
(-1125 1825);
PAINT GREEN (-1125 1825);
DISPLAY INVISIBLE (-1125 1825);
FORCEADD CAP..1
(-1350 625);
FORCEPROP 1 LAST LOCATION C1L19
J 0
(-1300 725);
DISPLAY 0.617021 (-1300 725);
PAINT AQUA (-1300 725);
FORCEPROP 1 LAST PART_NUMBER D97712-011
J 0
(-1300 475);
DISPLAY 0.617021 (-1300 475);
PAINT BLUE (-1300 475);
FORCEPROP 1 LAST VALUE 1.0UF
J 0
(-1300 675);
DISPLAY 0.617021 (-1300 675);
PAINT SKYBLUE (-1300 675);
FORCEPROP 1 LAST TOLERANCE 10%
J 0
(-1300 575);
DISPLAY 0.617021 (-1300 575);
PAINT SKYBLUE (-1300 575);
FORCEPROP 1 LAST PACK_TYPE 0402
J 0
(-1300 425);
DISPLAY 0.617021 (-1300 425);
PAINT SKYBLUE (-1300 425);
FORCEPROP 1 LAST VOLTAGE 16V
J 0
(-1300 625);
DISPLAY 0.617021 (-1300 625);
PAINT SKYBLUE (-1300 625);
FORCEPROP 1 LAST MATERIAL X6S
J 0
(-1300 525);
DISPLAY 0.617021 (-1300 525);
PAINT SKYBLUE (-1300 525);
FORCEPROP 1 LASTPIN (-1350 525) $PN 2
J 0
(-1340 505);
DISPLAY 0.617021 (-1340 505);
PAINT ORANGE (-1340 505);
FORCEPROP 1 LASTPIN (-1350 725) $PN 1
J 0
(-1340 705);
DISPLAY 0.617021 (-1340 705);
PAINT ORANGE (-1340 705);
FORCEPROP 2 LAST CDS_LIB mstr_discrete
J 0
(-1350 625);
PAINT MONO (-1350 625);
DISPLAY INVISIBLE (-1350 625);
FORCEPROP 2 LAST SEC_TYPE 0402
J 0
(-1300 825);
DISPLAY 1.021277 (-1300 825);
PAINT ORANGE (-1300 825);
DISPLAY INVISIBLE (-1300 825);
FORCEPROP 2 LAST SEC 1
J 0
(-1300 825);
DISPLAY 0.680851 (-1300 825);
PAINT MONO (-1300 825);
DISPLAY INVISIBLE (-1300 825);
FORCEPROP 2 LAST CDS_LOCATION C1L19
J 0
(-1300 725);
DISPLAY 0.617021 (-1300 725);
PAINT AQUA (-1300 725);
DISPLAY INVISIBLE (-1300 725);
FORCEPROP 1 LAST PATH I140
J 0
(-1300 775);
DISPLAY 0.978723 (-1300 775);
PAINT WHITE (-1300 775);
DISPLAY INVISIBLE (-1300 775);
FORCEPROP 0 LAST ROOM DEBUG
J 0
(-1300 825);
DISPLAY 1.021277 (-1300 825);
PAINT ORANGE (-1300 825);
DISPLAY INVISIBLE (-1300 825);
FORCEADD GND..1
(-1350 450);
FORCEPROP 3 LASTPIN (-1350 500) SIG_NAME GND\g
J 0
(-1340 510);
DISPLAY 0.659574 (-1340 510);
PAINT MONO (-1340 510);
DISPLAY INVISIBLE (-1340 510);
FORCEPROP 1 LAST VOLTAGE 0.0V
J 0
(-1395 407);
DISPLAY 0.340426 (-1395 407);
PAINT SKYBLUE (-1395 407);
DISPLAY INVISIBLE (-1395 407);
FORCEPROP 1 LAST SIZE 1B
J 0
(-1275 400);
DISPLAY 2.382979 (-1275 400);
PAINT GREEN (-1275 400);
DISPLAY INVISIBLE (-1275 400);
FORCEPROP 2 LAST CDS_LIB mstr_symbols
J 0
(-1350 450);
PAINT MONO (-1350 450);
DISPLAY INVISIBLE (-1350 450);
FORCEPROP 1 LAST BODY_TYPE PLUMBING
J 0
(-1395 407);
DISPLAY 0.340426 (-1395 407);
PAINT GREEN (-1395 407);
DISPLAY INVISIBLE (-1395 407);
FORCEPROP 1 LAST PATH I141
J 0
(-1275 450);
DISPLAY 0.872340 (-1275 450);
PAINT AQUA (-1275 450);
DISPLAY INVISIBLE (-1275 450);
FORCEPROP 1 LAST HDL_POWER GND
J 0
(-1350 600);
PAINT GREEN (-1350 600);
DISPLAY INVISIBLE (-1350 600);
FORCEADD P3V3_STBY..1
(3550 3925);
FORCEPROP 3 LASTPIN (3550 3875) SIG_NAME P3V3_STBY\g
J 0
(3560 3885);
DISPLAY 0.659574 (3560 3885);
PAINT MONO (3560 3885);
DISPLAY INVISIBLE (3560 3885);
FORCEPROP 1 LAST VOLTAGE +3.3V
J 0
(3750 4075);
DISPLAY 1.021277 (3750 4075);
PAINT SKYBLUE (3750 4075);
DISPLAY INVISIBLE (3750 4075);
FORCEPROP 2 LAST CDS_LIB mstr_symbols
J 0
(3550 3925);
PAINT ORANGE (3550 3925);
DISPLAY INVISIBLE (3550 3925);
FORCEPROP 1 LAST SIZE 1B
J 0
(3595 3947);
DISPLAY 0.340426 (3595 3947);
PAINT GREEN (3595 3947);
DISPLAY INVISIBLE (3595 3947);
FORCEPROP 1 LAST BODY_TYPE PLUMBING
J 0
(3505 3882);
DISPLAY 0.340426 (3505 3882);
PAINT GREEN (3505 3882);
DISPLAY INVISIBLE (3505 3882);
FORCEPROP 1 LAST PATH I143
J 0
(3595 3927);
DISPLAY 0.340426 (3595 3927);
PAINT GREEN (3595 3927);
DISPLAY INVISIBLE (3595 3927);
FORCEPROP 1 LAST HDL_POWER P3V3_STBY
J 0
(3250 3800);
DISPLAY 0.872340 (3250 3800);
PAINT ORANGE (3250 3800);
DISPLAY INVISIBLE (3250 3800);
FORCEADD P3V3_STBY..1
(2700 4300);
FORCEPROP 3 LASTPIN (2700 4250) SIG_NAME P3V3_STBY\g
J 0
(2710 4260);
DISPLAY 0.659574 (2710 4260);
PAINT MONO (2710 4260);
DISPLAY INVISIBLE (2710 4260);
FORCEPROP 1 LAST VOLTAGE +3.3V
J 0
(2900 4450);
DISPLAY 1.021277 (2900 4450);
PAINT SKYBLUE (2900 4450);
DISPLAY INVISIBLE (2900 4450);
FORCEPROP 1 LAST SIZE 1B
J 0
(2745 4322);
DISPLAY 0.340426 (2745 4322);
PAINT GREEN (2745 4322);
DISPLAY INVISIBLE (2745 4322);
FORCEPROP 2 LAST CDS_LIB mstr_symbols
J 0
(2700 4300);
PAINT ORANGE (2700 4300);
DISPLAY INVISIBLE (2700 4300);
FORCEPROP 1 LAST BODY_TYPE PLUMBING
J 0
(2655 4257);
DISPLAY 0.340426 (2655 4257);
PAINT GREEN (2655 4257);
DISPLAY INVISIBLE (2655 4257);
FORCEPROP 1 LAST PATH I144
J 0
(2745 4302);
DISPLAY 0.340426 (2745 4302);
PAINT GREEN (2745 4302);
DISPLAY INVISIBLE (2745 4302);
FORCEPROP 1 LAST HDL_POWER P3V3_STBY
J 0
(2400 4175);
DISPLAY 0.872340 (2400 4175);
PAINT ORANGE (2400 4175);
DISPLAY INVISIBLE (2400 4175);
FORCEADD OFFPAGE..1
R 2
(3650 4725);
FORCEPROP 2 LAST $XR0 55 
J 0
(3836 4725);
DISPLAY 0.638298 (3836 4725);
PAINT MONO (3836 4725);
FORCEPROP 2 LAST $XR1 112 
J 0
(3926 4725);
DISPLAY 0.638298 (3926 4725);
PAINT MONO (3926 4725);
FORCEPROP 2 LAST ROOM CPU_JTAG_DEBUG
J 0
(3850 4775);
DISPLAY 1.617021 (3850 4775);
PAINT WHITE (3850 4775);
DISPLAY INVISIBLE (3850 4775);
FORCEPROP 2 LAST BOM_COST DEBUG
J 0
(3850 4825);
DISPLAY 1.617021 (3850 4825);
PAINT WHITE (3850 4825);
DISPLAY INVISIBLE (3850 4825);
FORCEPROP 2 LAST CDS_LIB mstr_standard
J 0
(3650 4725);
PAINT ORANGE (3650 4725);
DISPLAY INVISIBLE (3650 4725);
FORCEPROP 1 LAST OFFPAGE TRUE
J 2
(3325 4600);
DISPLAY 1.404255 (3325 4600);
PAINT GREEN (3325 4600);
DISPLAY INVISIBLE (3325 4600);
FORCEPROP 1 LAST COMMENT_BODY TRUE
J 2
(3525 4625);
DISPLAY 1.404255 (3525 4625);
PAINT PEACH (3525 4625);
DISPLAY INVISIBLE (3525 4625);
FORCEPROP 2 LAST PATH I145
J 0
(3825 4800);
DISPLAY 1.021277 (3825 4800);
PAINT ORANGE (3825 4800);
DISPLAY INVISIBLE (3825 4800);
FORCEADD OFFPAGE..1
R 2
(3650 4625);
FORCEPROP 2 LAST $XR0 21 
J 0
(3836 4625);
DISPLAY 0.638298 (3836 4625);
PAINT MONO (3836 4625);
FORCEPROP 2 LAST $XR1 112 
J 0
(3926 4625);
DISPLAY 0.638298 (3926 4625);
PAINT MONO (3926 4625);
FORCEPROP 2 LAST ROOM CPU_JTAG_DEBUG
J 0
(3850 4675);
DISPLAY 1.617021 (3850 4675);
PAINT WHITE (3850 4675);
DISPLAY INVISIBLE (3850 4675);
FORCEPROP 2 LAST BOM_COST DEBUG
J 0
(3850 4725);
DISPLAY 1.617021 (3850 4725);
PAINT WHITE (3850 4725);
DISPLAY INVISIBLE (3850 4725);
FORCEPROP 2 LAST CDS_LIB mstr_standard
J 0
(3650 4625);
PAINT ORANGE (3650 4625);
DISPLAY INVISIBLE (3650 4625);
FORCEPROP 1 LAST OFFPAGE TRUE
J 2
(3325 4500);
DISPLAY 1.404255 (3325 4500);
PAINT GREEN (3325 4500);
DISPLAY INVISIBLE (3325 4500);
FORCEPROP 1 LAST COMMENT_BODY TRUE
J 2
(3525 4525);
DISPLAY 1.404255 (3525 4525);
PAINT PEACH (3525 4525);
DISPLAY INVISIBLE (3525 4525);
FORCEPROP 2 LAST PATH I146
J 0
(3825 4700);
DISPLAY 1.021277 (3825 4700);
PAINT ORANGE (3825 4700);
DISPLAY INVISIBLE (3825 4700);
FORCEADD PVCCIO_CPU0..1
(2675 2700);
FORCEPROP 3 LASTPIN (2675 2650) SIG_NAME PVCCIO_CPU0\g
J 0
(2685 2660);
DISPLAY 0.659574 (2685 2660);
PAINT MONO (2685 2660);
DISPLAY INVISIBLE (2685 2660);
FORCEPROP 1 LAST VOLTAGE 1.1V
J 0
(2630 2657);
DISPLAY 0.340426 (2630 2657);
PAINT SKYBLUE (2630 2657);
DISPLAY INVISIBLE (2630 2657);
FORCEPROP 2 LAST CDS_LIB mstr_symbols
J 0
(2675 2700);
PAINT ORANGE (2675 2700);
DISPLAY INVISIBLE (2675 2700);
FORCEPROP 1 LAST BODY_TYPE PLUMBING
J 0
(2630 2657);
DISPLAY 0.340426 (2630 2657);
PAINT GREEN (2630 2657);
DISPLAY INVISIBLE (2630 2657);
FORCEPROP 1 LAST PATH I147
J 0
(2725 2725);
DISPLAY 0.872340 (2725 2725);
PAINT AQUA (2725 2725);
DISPLAY INVISIBLE (2725 2725);
FORCEPROP 1 LAST HDL_POWER PVCCIO_CPU0
J 1
(2675 2750);
DISPLAY 0.872340 (2675 2750);
PAINT GREEN (2675 2750);
DISPLAY INVISIBLE (2675 2750);
FORCEADD P3V3_STBY..1
(-1125 2050);
FORCEPROP 3 LASTPIN (-1125 2000) SIG_NAME P3V3_STBY\g
J 0
(-1115 2010);
DISPLAY 0.659574 (-1115 2010);
PAINT MONO (-1115 2010);
DISPLAY INVISIBLE (-1115 2010);
FORCEPROP 1 LAST VOLTAGE +3.3V
J 0
(-925 2200);
DISPLAY 1.021277 (-925 2200);
PAINT SKYBLUE (-925 2200);
DISPLAY INVISIBLE (-925 2200);
FORCEPROP 2 LAST CDS_LIB mstr_symbols
J 0
(-1125 2050);
PAINT ORANGE (-1125 2050);
DISPLAY INVISIBLE (-1125 2050);
FORCEPROP 1 LAST SIZE 1B
J 0
(-1080 2072);
DISPLAY 0.340426 (-1080 2072);
PAINT GREEN (-1080 2072);
DISPLAY INVISIBLE (-1080 2072);
FORCEPROP 1 LAST BODY_TYPE PLUMBING
J 0
(-1170 2007);
DISPLAY 0.340426 (-1170 2007);
PAINT GREEN (-1170 2007);
DISPLAY INVISIBLE (-1170 2007);
FORCEPROP 1 LAST PATH I148
J 0
(-1080 2052);
DISPLAY 0.340426 (-1080 2052);
PAINT GREEN (-1080 2052);
DISPLAY INVISIBLE (-1080 2052);
FORCEPROP 1 LAST HDL_POWER P3V3_STBY
J 0
(-1425 1925);
DISPLAY 0.872340 (-1425 1925);
PAINT ORANGE (-1425 1925);
DISPLAY INVISIBLE (-1425 1925);
FORCEADD P3V3_STBY..1
(-1350 800);
FORCEPROP 3 LASTPIN (-1350 750) SIG_NAME P3V3_STBY\g
J 0
(-1340 760);
DISPLAY 0.659574 (-1340 760);
PAINT MONO (-1340 760);
DISPLAY INVISIBLE (-1340 760);
FORCEPROP 1 LAST VOLTAGE +3.3V
J 0
(-1150 950);
DISPLAY 1.021277 (-1150 950);
PAINT SKYBLUE (-1150 950);
DISPLAY INVISIBLE (-1150 950);
FORCEPROP 1 LAST SIZE 1B
J 0
(-1305 822);
DISPLAY 0.340426 (-1305 822);
PAINT GREEN (-1305 822);
DISPLAY INVISIBLE (-1305 822);
FORCEPROP 2 LAST CDS_LIB mstr_symbols
J 0
(-1350 800);
PAINT ORANGE (-1350 800);
DISPLAY INVISIBLE (-1350 800);
FORCEPROP 1 LAST BODY_TYPE PLUMBING
J 0
(-1395 757);
DISPLAY 0.340426 (-1395 757);
PAINT GREEN (-1395 757);
DISPLAY INVISIBLE (-1395 757);
FORCEPROP 1 LAST PATH I149
J 0
(-1305 802);
DISPLAY 0.340426 (-1305 802);
PAINT GREEN (-1305 802);
DISPLAY INVISIBLE (-1305 802);
FORCEPROP 1 LAST HDL_POWER P3V3_STBY
J 0
(-1650 675);
DISPLAY 0.872340 (-1650 675);
PAINT ORANGE (-1650 675);
DISPLAY INVISIBLE (-1650 675);
FORCEADD OFFPAGE..1
R 2
(3650 4825);
FORCEPROP 2 LAST $XR0 55 
J 0
(3836 4825);
DISPLAY 0.638298 (3836 4825);
PAINT MONO (3836 4825);
FORCEPROP 2 LAST $XR1 112 
J 0
(3926 4825);
DISPLAY 0.638298 (3926 4825);
PAINT MONO (3926 4825);
FORCEPROP 2 LAST $XR2 118 
J 0
(4046 4825);
DISPLAY 0.638298 (4046 4825);
PAINT MONO (4046 4825);
FORCEPROP 2 LAST $XR3 144 
J 0
(3836 4789);
DISPLAY 0.638298 (3836 4789);
PAINT MONO (3836 4789);
FORCEPROP 2 LAST $XR4 190 
J 0
(3956 4789);
DISPLAY 0.638298 (3956 4789);
PAINT MONO (3956 4789);
FORCEPROP 2 LAST CDS_LIB mstr_standard
J 2
(3650 4825);
DISPLAY 2.212766 (3650 4825);
PAINT ORANGE (3650 4825);
DISPLAY INVISIBLE (3650 4825);
FORCEPROP 2 LAST ROOM CPU_JTAG_DEBUG
J 0
(3850 4875);
DISPLAY 1.617021 (3850 4875);
PAINT WHITE (3850 4875);
DISPLAY INVISIBLE (3850 4875);
FORCEPROP 2 LAST BOM_COST DEBUG
J 0
(3850 4925);
DISPLAY 1.617021 (3850 4925);
PAINT WHITE (3850 4925);
DISPLAY INVISIBLE (3850 4925);
FORCEPROP 1 LAST OFFPAGE TRUE
J 2
(3325 4700);
DISPLAY 1.404255 (3325 4700);
PAINT GREEN (3325 4700);
DISPLAY INVISIBLE (3325 4700);
FORCEPROP 1 LAST COMMENT_BODY TRUE
J 2
(3525 4725);
DISPLAY 1.404255 (3525 4725);
PAINT PEACH (3525 4725);
DISPLAY INVISIBLE (3525 4725);
FORCEPROP 2 LAST PATH I36
J 0
(4025 4875);
DISPLAY 1.021277 (4025 4875);
PAINT ORANGE (4025 4875);
DISPLAY INVISIBLE (4025 4875);
FORCEADD GND..1
(2175 4450);
FORCEPROP 3 LASTPIN (2175 4500) SIG_NAME GND\g
J 0
(2185 4510);
DISPLAY 0.659574 (2185 4510);
PAINT MONO (2185 4510);
DISPLAY INVISIBLE (2185 4510);
FORCEPROP 1 LAST VOLTAGE 0.0V
J 0
(2130 4407);
DISPLAY 0.340426 (2130 4407);
PAINT SKYBLUE (2130 4407);
DISPLAY INVISIBLE (2130 4407);
FORCEPROP 2 LAST BOM_COST DEBUG
J 0
(1700 4575);
DISPLAY 1.617021 (1700 4575);
PAINT WHITE (1700 4575);
DISPLAY INVISIBLE (1700 4575);
FORCEPROP 2 LAST CDS_LIB mstr_symbols
J 0
(2175 4450);
DISPLAY 2.212766 (2175 4450);
PAINT ORANGE (2175 4450);
DISPLAY INVISIBLE (2175 4450);
FORCEPROP 1 LAST SIZE 1B
J 0
(2250 4400);
DISPLAY 1.893617 (2250 4400);
PAINT GREEN (2250 4400);
DISPLAY INVISIBLE (2250 4400);
FORCEPROP 1 LAST BODY_TYPE PLUMBING
J 0
(2130 4407);
DISPLAY 0.340426 (2130 4407);
PAINT GREEN (2130 4407);
DISPLAY INVISIBLE (2130 4407);
FORCEPROP 1 LAST PATH I39
J 0
(2250 4450);
DISPLAY 0.872340 (2250 4450);
PAINT AQUA (2250 4450);
DISPLAY INVISIBLE (2250 4450);
FORCEPROP 2 LAST ROOM CPU_JTAG_DEBUG
J 0
(1700 4525);
DISPLAY 1.617021 (1700 4525);
PAINT WHITE (1700 4525);
DISPLAY INVISIBLE (1700 4525);
FORCEPROP 1 LAST HDL_POWER GND
J 0
(2175 4600);
PAINT GREEN (2175 4600);
DISPLAY INVISIBLE (2175 4600);
FORCEADD NC7SB3157..1
R 2
(2600 4675);
FORCEPROP 1 LAST LOCATION U1M7
J 2
(2900 4950);
DISPLAY 0.617021 (2900 4950);
PAINT AQUA (2900 4950);
FORCEPROP 1 LAST PART_NUMBER C99406-001
J 2
(2900 4900);
DISPLAY 0.617021 (2900 4900);
PAINT BLUE (2900 4900);
FORCEPROP 1 LAST PACK_TYPE SMLF
J 2
(2775 4425);
DISPLAY 0.617021 (2775 4425);
PAINT SKYBLUE (2775 4425);
FORCEPROP 1 LAST MATERIAL IC
J 2
(2900 4425);
DISPLAY 0.617021 (2900 4425);
PAINT SKYBLUE (2900 4425);
FORCEPROP 2 LASTPIN (2950 4525) $PN 5
J 0
(2960 4535);
DISPLAY 0.617021 (2960 4535);
PAINT WHITE (2960 4535);
FORCEPROP 2 LASTPIN (2950 4825) $PN 6
J 0
(2960 4835);
DISPLAY 0.617021 (2960 4835);
PAINT WHITE (2960 4835);
FORCEPROP 2 LASTPIN (2250 4525) $PN 2
J 2
(2240 4535);
DISPLAY 0.617021 (2240 4535);
PAINT WHITE (2240 4535);
FORCEPROP 2 LASTPIN (2950 4625) $PN 1
J 0
(2960 4635);
DISPLAY 0.617021 (2960 4635);
PAINT WHITE (2960 4635);
FORCEPROP 2 LASTPIN (2950 4725) $PN 3
J 0
(2960 4735);
DISPLAY 0.617021 (2960 4735);
PAINT WHITE (2960 4735);
FORCEPROP 2 LASTPIN (2250 4675) $PN 4
J 2
(2240 4685);
DISPLAY 0.617021 (2240 4685);
PAINT WHITE (2240 4685);
FORCEPROP 2 LAST BOM_COST DEBUG
J 0
(2900 5050);
DISPLAY 1.617021 (2900 5050);
PAINT WHITE (2900 5050);
DISPLAY INVISIBLE (2900 5050);
FORCEPROP 2 LAST CDS_LIB mstr_analog
J 2
(2600 4675);
DISPLAY 2.212766 (2600 4675);
PAINT ORANGE (2600 4675);
DISPLAY INVISIBLE (2600 4675);
FORCEPROP 2 LAST CDS_SEC 1
J 0
(2900 5000);
PAINT MONO (2900 5000);
DISPLAY INVISIBLE (2900 5000);
FORCEPROP 2 LAST $SEC 1
J 0
(2900 5000);
PAINT MONO (2900 5000);
DISPLAY INVISIBLE (2900 5000);
FORCEPROP 1 LAST PATH I40
J 2
(2525 4425);
DISPLAY 0.851064 (2525 4425);
PAINT WHITE (2525 4425);
DISPLAY INVISIBLE (2525 4425);
FORCEPROP 2 LAST ROOM DEBUG
J 0
(2900 5000);
DISPLAY 1.617021 (2900 5000);
PAINT WHITE (2900 5000);
DISPLAY INVISIBLE (2900 5000);
FORCEADD OFFPAGE..2
R 2
(1775 4675);
FORCEPROP 2 LAST $XR0 112 
J 0
(1520 4675);
DISPLAY 0.638298 (1520 4675);
PAINT MONO (1520 4675);
FORCEPROP 2 LAST CDS_LIB mstr_standard
J 2
(1775 4675);
PAINT ORANGE (1775 4675);
DISPLAY INVISIBLE (1775 4675);
FORCEPROP 1 LAST OFFPAGE TRUE
J 2
(1450 4550);
DISPLAY 0.872340 (1450 4550);
PAINT GREEN (1450 4550);
DISPLAY INVISIBLE (1450 4550);
FORCEPROP 1 LAST COMMENT_BODY TRUE
J 2
(1820 4580);
DISPLAY 0.872340 (1820 4580);
PAINT GREEN (1820 4580);
DISPLAY INVISIBLE (1820 4580);
FORCEPROP 2 LAST PATH I41
J 2
(1975 4725);
DISPLAY 1.021277 (1975 4725);
PAINT ORANGE (1975 4725);
DISPLAY INVISIBLE (1975 4725);
FORCEADD CAP_A..1
R 2
(3100 4025);
FORCEPROP 1 LAST LOCATION C1M36
J 2
(3050 4125);
DISPLAY 0.617021 (3050 4125);
PAINT AQUA (3050 4125);
FORCEPROP 1 LAST PART_NUMBER A36096-045
J 2
(3050 3875);
DISPLAY 0.617021 (3050 3875);
PAINT BLUE (3050 3875);
FORCEPROP 1 LAST VALUE 0.01UF
J 2
(3050 4075);
DISPLAY 0.617021 (3050 4075);
PAINT SKYBLUE (3050 4075);
FORCEPROP 1 LAST TOLERANCE 10%
J 2
(3050 3975);
DISPLAY 0.617021 (3050 3975);
PAINT SKYBLUE (3050 3975);
FORCEPROP 1 LAST PACK_TYPE 0402V
J 2
(3050 3825);
DISPLAY 0.617021 (3050 3825);
PAINT SKYBLUE (3050 3825);
FORCEPROP 1 LAST VOLTAGE 25V
J 2
(3050 4025);
DISPLAY 0.617021 (3050 4025);
PAINT SKYBLUE (3050 4025);
FORCEPROP 1 LAST MATERIAL X7R
J 2
(3050 3925);
DISPLAY 0.617021 (3050 3925);
PAINT SKYBLUE (3050 3925);
FORCEPROP 1 LASTPIN (3100 4125) $PN 1
J 2
(3090 4105);
DISPLAY 0.617021 (3090 4105);
PAINT WHITE (3090 4105);
FORCEPROP 1 LASTPIN (3100 3925) $PN 2
J 2
(3090 3905);
DISPLAY 0.617021 (3090 3905);
PAINT WHITE (3090 3905);
FORCEPROP 2 LAST BOM_COST DEBUG
J 0
(3050 4175);
DISPLAY 1.617021 (3050 4175);
PAINT WHITE (3050 4175);
DISPLAY INVISIBLE (3050 4175);
FORCEPROP 2 LAST CDS_LIB dev_discrete
J 0
(3100 4025);
PAINT ORANGE (3100 4025);
DISPLAY INVISIBLE (3100 4025);
FORCEPROP 2 LAST CDS_SEC 1
J 0
(3050 4175);
PAINT ORANGE (3050 4175);
DISPLAY INVISIBLE (3050 4175);
FORCEPROP 2 LAST SEC_TYPE 0402V
J 0
(3050 4175);
DISPLAY 1.659574 (3050 4175);
PAINT ORANGE (3050 4175);
DISPLAY INVISIBLE (3050 4175);
FORCEPROP 2 LAST SEC 1
J 2
(3050 4225);
DISPLAY 1.510638 (3050 4225);
PAINT MONO (3050 4225);
DISPLAY INVISIBLE (3050 4225);
FORCEPROP 1 LAST PATH I42
J 2
(3050 4175);
DISPLAY 0.978723 (3050 4175);
PAINT WHITE (3050 4175);
DISPLAY INVISIBLE (3050 4175);
FORCEPROP 2 LAST ROOM DEBUG
J 2
(3050 4175);
DISPLAY 1.617021 (3050 4175);
PAINT WHITE (3050 4175);
DISPLAY INVISIBLE (3050 4175);
FORCEADD CAP_A..1
R 2
(2700 4025);
FORCEPROP 1 LAST LOCATION C1M37
J 2
(2650 4125);
DISPLAY 0.617021 (2650 4125);
PAINT AQUA (2650 4125);
FORCEPROP 1 LAST PART_NUMBER D97712-004
J 2
(2650 3875);
DISPLAY 0.617021 (2650 3875);
PAINT BLUE (2650 3875);
FORCEPROP 1 LAST VALUE 1.0UF
J 2
(2650 4075);
DISPLAY 0.617021 (2650 4075);
PAINT SKYBLUE (2650 4075);
FORCEPROP 1 LAST TOLERANCE 10%
J 2
(2650 3975);
DISPLAY 0.617021 (2650 3975);
PAINT SKYBLUE (2650 3975);
FORCEPROP 1 LAST PACK_TYPE 0402V
J 2
(2650 3825);
DISPLAY 0.617021 (2650 3825);
PAINT SKYBLUE (2650 3825);
FORCEPROP 1 LAST VOLTAGE 6.3V
J 2
(2650 4025);
DISPLAY 0.617021 (2650 4025);
PAINT SKYBLUE (2650 4025);
FORCEPROP 1 LAST MATERIAL X6S
J 2
(2650 3925);
DISPLAY 0.617021 (2650 3925);
PAINT SKYBLUE (2650 3925);
FORCEPROP 1 LASTPIN (2700 4125) $PN 1
J 2
(2690 4105);
DISPLAY 0.617021 (2690 4105);
PAINT WHITE (2690 4105);
FORCEPROP 1 LASTPIN (2700 3925) $PN 2
J 2
(2690 3905);
DISPLAY 0.617021 (2690 3905);
PAINT WHITE (2690 3905);
FORCEPROP 2 LAST BOM_COST DEBUG
J 0
(2650 4175);
DISPLAY 1.617021 (2650 4175);
PAINT WHITE (2650 4175);
DISPLAY INVISIBLE (2650 4175);
FORCEPROP 2 LAST CDS_LIB dev_discrete
J 0
(2700 4025);
PAINT ORANGE (2700 4025);
DISPLAY INVISIBLE (2700 4025);
FORCEPROP 2 LAST CDS_SEC 1
J 0
(2650 4225);
PAINT MONO (2650 4225);
DISPLAY INVISIBLE (2650 4225);
FORCEPROP 2 LAST $SEC 1
J 0
(2650 4225);
PAINT MONO (2650 4225);
DISPLAY INVISIBLE (2650 4225);
FORCEPROP 1 LAST PATH I47
J 2
(2650 4175);
DISPLAY 0.978723 (2650 4175);
PAINT WHITE (2650 4175);
DISPLAY INVISIBLE (2650 4175);
FORCEPROP 2 LAST ROOM DEBUG
J 2
(2650 4175);
DISPLAY 1.617021 (2650 4175);
PAINT WHITE (2650 4175);
DISPLAY INVISIBLE (2650 4175);
FORCEADD GND..1
(2700 3675);
FORCEPROP 3 LASTPIN (2700 3725) SIG_NAME GND\g
J 0
(2710 3735);
DISPLAY 0.659574 (2710 3735);
PAINT MONO (2710 3735);
DISPLAY INVISIBLE (2710 3735);
FORCEPROP 1 LAST VOLTAGE 0.0V
J 0
(2655 3632);
DISPLAY 0.340426 (2655 3632);
PAINT SKYBLUE (2655 3632);
DISPLAY INVISIBLE (2655 3632);
FORCEPROP 2 LAST BOM_COST DEBUG
J 0
(2225 3800);
DISPLAY 1.617021 (2225 3800);
PAINT WHITE (2225 3800);
DISPLAY INVISIBLE (2225 3800);
FORCEPROP 2 LAST CDS_LIB mstr_symbols
J 0
(2700 3675);
DISPLAY 2.212766 (2700 3675);
PAINT ORANGE (2700 3675);
DISPLAY INVISIBLE (2700 3675);
FORCEPROP 1 LAST SIZE 1B
J 0
(2775 3625);
DISPLAY 1.893617 (2775 3625);
PAINT GREEN (2775 3625);
DISPLAY INVISIBLE (2775 3625);
FORCEPROP 1 LAST BODY_TYPE PLUMBING
J 0
(2655 3632);
DISPLAY 0.340426 (2655 3632);
PAINT GREEN (2655 3632);
DISPLAY INVISIBLE (2655 3632);
FORCEPROP 1 LAST PATH I48
J 0
(2775 3675);
DISPLAY 0.872340 (2775 3675);
PAINT AQUA (2775 3675);
DISPLAY INVISIBLE (2775 3675);
FORCEPROP 2 LAST ROOM CPU_JTAG_DEBUG
J 0
(2225 3750);
DISPLAY 1.617021 (2225 3750);
PAINT WHITE (2225 3750);
DISPLAY INVISIBLE (2225 3750);
FORCEPROP 1 LAST HDL_POWER GND
J 0
(2700 3825);
PAINT GREEN (2700 3825);
DISPLAY INVISIBLE (2700 3825);
FORCEADD RES..2
(2675 2400);
FORCEPROP 1 LAST LOCATION R6P46
J 0
(2720 2525);
DISPLAY 0.617021 (2720 2525);
PAINT AQUA (2720 2525);
FORCEPROP 1 LAST PART_NUMBER G21796-017
J 0
(2715 2275);
DISPLAY 0.617021 (2715 2275);
PAINT BLUE (2715 2275);
FORCEPROP 1 LAST VALUE 100.0
J 0
(2720 2475);
DISPLAY 0.617021 (2720 2475);
PAINT SKYBLUE (2720 2475);
FORCEPROP 1 LAST TOLERANCE 1%
J 0
(2720 2425);
DISPLAY 0.617021 (2720 2425);
PAINT SKYBLUE (2720 2425);
FORCEPROP 1 LAST PACK_TYPE 0402
J 0
(2715 2225);
DISPLAY 0.617021 (2715 2225);
PAINT SKYBLUE (2715 2225);
FORCEPROP 1 LAST MATERIAL CHIP
J 0
(2715 2325);
DISPLAY 0.617021 (2715 2325);
PAINT SKYBLUE (2715 2325);
FORCEPROP 1 LAST WATTAGE 1/16W
J 0
(2715 2375);
DISPLAY 0.617021 (2715 2375);
PAINT SKYBLUE (2715 2375);
FORCEPROP 1 LASTPIN (2675 2300) $PN 2
J 0
(2680 2310);
DISPLAY 0.617021 (2680 2310);
PAINT ORANGE (2680 2310);
FORCEPROP 1 LASTPIN (2675 2500) $PN 1
J 0
(2680 2462);
DISPLAY 0.617021 (2680 2462);
PAINT ORANGE (2680 2462);
FORCEPROP 2 LAST CDS_LIB mstr_discrete
J 0
(2675 2400);
PAINT ORANGE (2675 2400);
DISPLAY INVISIBLE (2675 2400);
FORCEPROP 2 LAST SEC_TYPE 0402
J 0
(2725 2625);
DISPLAY 1.021277 (2725 2625);
PAINT ORANGE (2725 2625);
DISPLAY INVISIBLE (2725 2625);
FORCEPROP 2 LAST SEC 1
J 0
(2725 2625);
DISPLAY 0.680851 (2725 2625);
PAINT MONO (2725 2625);
DISPLAY INVISIBLE (2725 2625);
FORCEPROP 2 LAST CDS_LOCATION R6P46
J 0
(2720 2525);
DISPLAY 0.617021 (2720 2525);
PAINT AQUA (2720 2525);
DISPLAY INVISIBLE (2720 2525);
FORCEPROP 1 LAST PATH I49
J 0
(2725 2575);
DISPLAY 0.978723 (2725 2575);
PAINT WHITE (2725 2575);
DISPLAY INVISIBLE (2725 2575);
FORCEPROP 2 LAST ROOM DEBUG
J 0
(2720 2565);
DISPLAY 1.276596 (2720 2565);
PAINT WHITE (2720 2565);
DISPLAY INVISIBLE (2720 2565);
FORCEADD RES..2
(2325 2400);
FORCEPROP 1 LAST LOCATION R7P30
J 0
(2370 2525);
DISPLAY 0.617021 (2370 2525);
PAINT AQUA (2370 2525);
FORCEPROP 1 LAST PART_NUMBER G21796-017
J 0
(2365 2275);
DISPLAY 0.617021 (2365 2275);
PAINT BLUE (2365 2275);
FORCEPROP 1 LAST VALUE 100.0
J 0
(2370 2475);
DISPLAY 0.617021 (2370 2475);
PAINT SKYBLUE (2370 2475);
FORCEPROP 1 LAST TOLERANCE 1%
J 0
(2370 2425);
DISPLAY 0.617021 (2370 2425);
PAINT SKYBLUE (2370 2425);
FORCEPROP 1 LAST PACK_TYPE 0402
J 0
(2365 2225);
DISPLAY 0.617021 (2365 2225);
PAINT SKYBLUE (2365 2225);
FORCEPROP 1 LAST MATERIAL CHIP
J 0
(2365 2325);
DISPLAY 0.617021 (2365 2325);
PAINT SKYBLUE (2365 2325);
FORCEPROP 1 LAST WATTAGE 1/16W
J 0
(2365 2375);
DISPLAY 0.617021 (2365 2375);
PAINT SKYBLUE (2365 2375);
FORCEPROP 1 LASTPIN (2325 2300) $PN 2
J 0
(2330 2310);
DISPLAY 0.617021 (2330 2310);
PAINT ORANGE (2330 2310);
FORCEPROP 1 LASTPIN (2325 2500) $PN 1
J 0
(2330 2462);
DISPLAY 0.617021 (2330 2462);
PAINT ORANGE (2330 2462);
FORCEPROP 2 LAST CDS_LIB mstr_discrete
J 0
(2325 2400);
PAINT ORANGE (2325 2400);
DISPLAY INVISIBLE (2325 2400);
FORCEPROP 2 LAST SEC_TYPE 0402
J 0
(2375 2625);
DISPLAY 1.021277 (2375 2625);
PAINT ORANGE (2375 2625);
DISPLAY INVISIBLE (2375 2625);
FORCEPROP 2 LAST SEC 1
J 0
(2375 2625);
DISPLAY 0.680851 (2375 2625);
PAINT MONO (2375 2625);
DISPLAY INVISIBLE (2375 2625);
FORCEPROP 2 LAST CDS_LOCATION R7P30
J 0
(2370 2525);
DISPLAY 0.617021 (2370 2525);
PAINT AQUA (2370 2525);
DISPLAY INVISIBLE (2370 2525);
FORCEPROP 1 LAST PATH I50
J 0
(2375 2575);
DISPLAY 0.978723 (2375 2575);
PAINT WHITE (2375 2575);
DISPLAY INVISIBLE (2375 2575);
FORCEPROP 2 LAST ROOM DEBUG
J 0
(2370 2565);
DISPLAY 1.276596 (2370 2565);
PAINT WHITE (2370 2565);
DISPLAY INVISIBLE (2370 2565);
FORCEADD RES..2
(1950 2400);
FORCEPROP 1 LAST LOCATION R1M3
J 0
(1995 2525);
DISPLAY 0.617021 (1995 2525);
PAINT AQUA (1995 2525);
FORCEPROP 1 LAST PART_NUMBER G21796-017
J 0
(1990 2275);
DISPLAY 0.617021 (1990 2275);
PAINT BLUE (1990 2275);
FORCEPROP 1 LAST VALUE 100.0
J 0
(1995 2475);
DISPLAY 0.617021 (1995 2475);
PAINT SKYBLUE (1995 2475);
FORCEPROP 1 LAST TOLERANCE 1%
J 0
(1995 2425);
DISPLAY 0.617021 (1995 2425);
PAINT SKYBLUE (1995 2425);
FORCEPROP 1 LAST PACK_TYPE 0402
J 0
(1990 2225);
DISPLAY 0.617021 (1990 2225);
PAINT SKYBLUE (1990 2225);
FORCEPROP 1 LAST MATERIAL CHIP
J 0
(1990 2325);
DISPLAY 0.617021 (1990 2325);
PAINT SKYBLUE (1990 2325);
FORCEPROP 1 LAST WATTAGE 1/16W
J 0
(1990 2375);
DISPLAY 0.617021 (1990 2375);
PAINT SKYBLUE (1990 2375);
FORCEPROP 1 LASTPIN (1950 2300) $PN 2
J 0
(1955 2310);
DISPLAY 0.617021 (1955 2310);
PAINT ORANGE (1955 2310);
FORCEPROP 1 LASTPIN (1950 2500) $PN 1
J 0
(1955 2462);
DISPLAY 0.617021 (1955 2462);
PAINT ORANGE (1955 2462);
FORCEPROP 2 LAST CDS_LIB mstr_discrete
J 0
(1950 2400);
PAINT ORANGE (1950 2400);
DISPLAY INVISIBLE (1950 2400);
FORCEPROP 2 LAST SEC_TYPE 0402
J 0
(2000 2625);
DISPLAY 1.021277 (2000 2625);
PAINT ORANGE (2000 2625);
DISPLAY INVISIBLE (2000 2625);
FORCEPROP 2 LAST SEC 1
J 0
(2000 2625);
DISPLAY 0.680851 (2000 2625);
PAINT MONO (2000 2625);
DISPLAY INVISIBLE (2000 2625);
FORCEPROP 2 LAST CDS_LOCATION R1M3
J 0
(1995 2525);
DISPLAY 0.617021 (1995 2525);
PAINT AQUA (1995 2525);
DISPLAY INVISIBLE (1995 2525);
FORCEPROP 1 LAST PATH I51
J 0
(2000 2575);
DISPLAY 0.978723 (2000 2575);
PAINT WHITE (2000 2575);
DISPLAY INVISIBLE (2000 2575);
FORCEPROP 2 LAST ROOM DEBUG
J 0
(1995 2565);
DISPLAY 1.276596 (1995 2565);
PAINT WHITE (1995 2565);
DISPLAY INVISIBLE (1995 2565);
FORCEADD PVCCIO_CPU0..1
(1175 4150);
FORCEPROP 3 LASTPIN (1175 4100) SIG_NAME PVCCIO_CPU0\g
J 0
(1185 4110);
DISPLAY 0.659574 (1185 4110);
PAINT MONO (1185 4110);
DISPLAY INVISIBLE (1185 4110);
FORCEPROP 1 LAST VOLTAGE 1.1V
J 0
(1130 4107);
DISPLAY 0.340426 (1130 4107);
PAINT SKYBLUE (1130 4107);
DISPLAY INVISIBLE (1130 4107);
FORCEPROP 2 LAST CDS_LIB mstr_symbols
J 0
(1175 4150);
PAINT ORANGE (1175 4150);
DISPLAY INVISIBLE (1175 4150);
FORCEPROP 1 LAST BODY_TYPE PLUMBING
J 0
(1130 4107);
DISPLAY 0.340426 (1130 4107);
PAINT GREEN (1130 4107);
DISPLAY INVISIBLE (1130 4107);
FORCEPROP 1 LAST PATH I52
J 0
(1225 4175);
DISPLAY 0.872340 (1225 4175);
PAINT AQUA (1225 4175);
DISPLAY INVISIBLE (1225 4175);
FORCEPROP 1 LAST HDL_POWER PVCCIO_CPU0
J 1
(1175 4200);
DISPLAY 0.872340 (1175 4200);
PAINT GREEN (1175 4200);
DISPLAY INVISIBLE (1175 4200);
FORCEADD RES..2
(1175 3800);
FORCEPROP 1 LAST LOCATION R4P15
J 0
(1220 3925);
DISPLAY 0.617021 (1220 3925);
PAINT AQUA (1220 3925);
FORCEPROP 1 LAST PART_NUMBER G21796-017
J 0
(1215 3675);
DISPLAY 0.617021 (1215 3675);
PAINT BLUE (1215 3675);
FORCEPROP 1 LAST VALUE 100.0
J 0
(1220 3875);
DISPLAY 0.617021 (1220 3875);
PAINT SKYBLUE (1220 3875);
FORCEPROP 1 LAST TOLERANCE 1%
J 0
(1220 3825);
DISPLAY 0.617021 (1220 3825);
PAINT SKYBLUE (1220 3825);
FORCEPROP 1 LAST PACK_TYPE 0402
J 0
(1215 3625);
DISPLAY 0.617021 (1215 3625);
PAINT SKYBLUE (1215 3625);
FORCEPROP 1 LAST MATERIAL CHIP
J 0
(1215 3725);
DISPLAY 0.617021 (1215 3725);
PAINT SKYBLUE (1215 3725);
FORCEPROP 1 LAST WATTAGE 1/16W
J 0
(1215 3775);
DISPLAY 0.617021 (1215 3775);
PAINT SKYBLUE (1215 3775);
FORCEPROP 1 LASTPIN (1175 3700) $PN 2
J 0
(1180 3710);
DISPLAY 0.617021 (1180 3710);
PAINT ORANGE (1180 3710);
FORCEPROP 1 LASTPIN (1175 3900) $PN 1
J 0
(1180 3862);
DISPLAY 0.617021 (1180 3862);
PAINT ORANGE (1180 3862);
FORCEPROP 2 LAST CDS_LIB mstr_discrete
J 0
(1175 3800);
PAINT MONO (1175 3800);
DISPLAY INVISIBLE (1175 3800);
FORCEPROP 2 LAST SEC_TYPE 0402
J 0
(1225 4025);
DISPLAY 1.021277 (1225 4025);
PAINT ORANGE (1225 4025);
DISPLAY INVISIBLE (1225 4025);
FORCEPROP 2 LAST SEC 1
J 0
(1225 4025);
DISPLAY 0.680851 (1225 4025);
PAINT MONO (1225 4025);
DISPLAY INVISIBLE (1225 4025);
FORCEPROP 2 LAST CDS_LOCATION R4P15
J 0
(1220 3925);
DISPLAY 0.617021 (1220 3925);
PAINT AQUA (1220 3925);
DISPLAY INVISIBLE (1220 3925);
FORCEPROP 1 LAST PATH I53
J 0
(1225 3975);
DISPLAY 0.978723 (1225 3975);
PAINT WHITE (1225 3975);
DISPLAY INVISIBLE (1225 3975);
FORCEPROP 2 LAST ROOM DEBUG
J 0
(1220 3965);
DISPLAY 1.276596 (1220 3965);
PAINT WHITE (1220 3965);
DISPLAY INVISIBLE (1220 3965);
FORCEADD RES..2
(1600 2400);
FORCEPROP 1 LAST LOCATION R1M4
J 0
(1645 2525);
DISPLAY 0.617021 (1645 2525);
PAINT AQUA (1645 2525);
FORCEPROP 1 LAST PART_NUMBER G21796-017
J 0
(1640 2275);
DISPLAY 0.617021 (1640 2275);
PAINT BLUE (1640 2275);
FORCEPROP 1 LAST VALUE 100.0
J 0
(1645 2475);
DISPLAY 0.617021 (1645 2475);
PAINT SKYBLUE (1645 2475);
FORCEPROP 1 LAST TOLERANCE 1%
J 0
(1645 2425);
DISPLAY 0.617021 (1645 2425);
PAINT SKYBLUE (1645 2425);
FORCEPROP 1 LAST PACK_TYPE 0402
J 0
(1640 2225);
DISPLAY 0.617021 (1640 2225);
PAINT SKYBLUE (1640 2225);
FORCEPROP 1 LAST MATERIAL CHIP
J 0
(1640 2325);
DISPLAY 0.617021 (1640 2325);
PAINT SKYBLUE (1640 2325);
FORCEPROP 1 LAST WATTAGE 1/16W
J 0
(1640 2375);
DISPLAY 0.617021 (1640 2375);
PAINT SKYBLUE (1640 2375);
FORCEPROP 1 LASTPIN (1600 2300) $PN 2
J 0
(1605 2310);
DISPLAY 0.617021 (1605 2310);
PAINT ORANGE (1605 2310);
FORCEPROP 1 LASTPIN (1600 2500) $PN 1
J 0
(1605 2462);
DISPLAY 0.617021 (1605 2462);
PAINT ORANGE (1605 2462);
FORCEPROP 2 LAST CDS_LIB mstr_discrete
J 0
(1600 2400);
PAINT ORANGE (1600 2400);
DISPLAY INVISIBLE (1600 2400);
FORCEPROP 2 LAST SEC_TYPE 0402
J 0
(1650 2625);
DISPLAY 1.021277 (1650 2625);
PAINT ORANGE (1650 2625);
DISPLAY INVISIBLE (1650 2625);
FORCEPROP 2 LAST SEC 1
J 0
(1650 2625);
DISPLAY 0.680851 (1650 2625);
PAINT MONO (1650 2625);
DISPLAY INVISIBLE (1650 2625);
FORCEPROP 2 LAST CDS_LOCATION R1M4
J 0
(1645 2525);
DISPLAY 0.617021 (1645 2525);
PAINT AQUA (1645 2525);
DISPLAY INVISIBLE (1645 2525);
FORCEPROP 1 LAST PATH I54
J 0
(1650 2575);
DISPLAY 0.978723 (1650 2575);
PAINT WHITE (1650 2575);
DISPLAY INVISIBLE (1650 2575);
FORCEPROP 2 LAST ROOM DEBUG
J 0
(1645 2565);
DISPLAY 1.276596 (1645 2565);
PAINT WHITE (1645 2565);
DISPLAY INVISIBLE (1645 2565);
FORCEADD RES..2
(1225 2400);
FORCEPROP 1 LAST LOCATION R6T7
J 0
(1270 2525);
DISPLAY 0.617021 (1270 2525);
PAINT AQUA (1270 2525);
FORCEPROP 1 LAST PART_NUMBER G21796-009
J 0
(1265 2275);
DISPLAY 0.617021 (1265 2275);
PAINT BLUE (1265 2275);
FORCEPROP 1 LAST VALUE 150.0
J 0
(1270 2475);
DISPLAY 0.617021 (1270 2475);
PAINT SKYBLUE (1270 2475);
FORCEPROP 1 LAST TOLERANCE 1%
J 0
(1270 2425);
DISPLAY 0.617021 (1270 2425);
PAINT SKYBLUE (1270 2425);
FORCEPROP 1 LAST PACK_TYPE 0402
J 0
(1265 2225);
DISPLAY 0.617021 (1265 2225);
PAINT SKYBLUE (1265 2225);
FORCEPROP 1 LAST MATERIAL CHIP
J 0
(1265 2325);
DISPLAY 0.617021 (1265 2325);
PAINT SKYBLUE (1265 2325);
FORCEPROP 1 LAST WATTAGE 1/16W
J 0
(1265 2375);
DISPLAY 0.617021 (1265 2375);
PAINT SKYBLUE (1265 2375);
FORCEPROP 1 LASTPIN (1225 2300) $PN 2
J 0
(1230 2310);
DISPLAY 0.617021 (1230 2310);
PAINT ORANGE (1230 2310);
FORCEPROP 1 LASTPIN (1225 2500) $PN 1
J 0
(1230 2462);
DISPLAY 0.617021 (1230 2462);
PAINT ORANGE (1230 2462);
FORCEPROP 2 LAST SEC_TYPE 0402
J 0
(1275 2625);
DISPLAY 1.021277 (1275 2625);
PAINT ORANGE (1275 2625);
DISPLAY INVISIBLE (1275 2625);
FORCEPROP 2 LAST CDS_LIB mstr_discrete
J 0
(1225 2400);
PAINT ORANGE (1225 2400);
DISPLAY INVISIBLE (1225 2400);
FORCEPROP 2 LAST SEC 1
J 0
(1275 2625);
DISPLAY 0.680851 (1275 2625);
PAINT MONO (1275 2625);
DISPLAY INVISIBLE (1275 2625);
FORCEPROP 2 LAST CDS_LOCATION R6T7
J 0
(1270 2525);
DISPLAY 0.617021 (1270 2525);
PAINT AQUA (1270 2525);
DISPLAY INVISIBLE (1270 2525);
FORCEPROP 1 LAST PATH I55
J 0
(1275 2575);
DISPLAY 0.978723 (1275 2575);
PAINT WHITE (1275 2575);
DISPLAY INVISIBLE (1275 2575);
FORCEPROP 2 LAST ROOM DEBUG
J 0
(1270 2565);
DISPLAY 1.276596 (1270 2565);
PAINT WHITE (1270 2565);
DISPLAY INVISIBLE (1270 2565);
FORCEADD RES..2
(875 2400);
FORCEPROP 1 LAST LOCATION R6T6
J 0
(920 2525);
DISPLAY 0.617021 (920 2525);
PAINT AQUA (920 2525);
FORCEPROP 1 LAST PART_NUMBER G21796-009
J 0
(915 2275);
DISPLAY 0.617021 (915 2275);
PAINT BLUE (915 2275);
FORCEPROP 1 LAST VALUE 150.0
J 0
(920 2475);
DISPLAY 0.617021 (920 2475);
PAINT SKYBLUE (920 2475);
FORCEPROP 1 LAST TOLERANCE 1%
J 0
(920 2425);
DISPLAY 0.617021 (920 2425);
PAINT SKYBLUE (920 2425);
FORCEPROP 1 LAST PACK_TYPE 0402
J 0
(915 2225);
DISPLAY 0.617021 (915 2225);
PAINT SKYBLUE (915 2225);
FORCEPROP 1 LAST MATERIAL CHIP
J 0
(915 2325);
DISPLAY 0.617021 (915 2325);
PAINT SKYBLUE (915 2325);
FORCEPROP 1 LAST WATTAGE 1/16W
J 0
(915 2375);
DISPLAY 0.617021 (915 2375);
PAINT SKYBLUE (915 2375);
FORCEPROP 1 LASTPIN (875 2300) $PN 2
J 0
(880 2310);
DISPLAY 0.617021 (880 2310);
PAINT ORANGE (880 2310);
FORCEPROP 1 LASTPIN (875 2500) $PN 1
J 0
(880 2462);
DISPLAY 0.617021 (880 2462);
PAINT ORANGE (880 2462);
FORCEPROP 2 LAST SEC_TYPE 0402
J 0
(925 2625);
DISPLAY 1.021277 (925 2625);
PAINT ORANGE (925 2625);
DISPLAY INVISIBLE (925 2625);
FORCEPROP 2 LAST CDS_LIB mstr_discrete
J 0
(875 2400);
PAINT ORANGE (875 2400);
DISPLAY INVISIBLE (875 2400);
FORCEPROP 2 LAST SEC 1
J 0
(925 2625);
DISPLAY 0.680851 (925 2625);
PAINT MONO (925 2625);
DISPLAY INVISIBLE (925 2625);
FORCEPROP 2 LAST CDS_LOCATION R6T6
J 0
(920 2525);
DISPLAY 0.617021 (920 2525);
PAINT AQUA (920 2525);
DISPLAY INVISIBLE (920 2525);
FORCEPROP 1 LAST PATH I56
J 0
(925 2575);
DISPLAY 0.978723 (925 2575);
PAINT WHITE (925 2575);
DISPLAY INVISIBLE (925 2575);
FORCEPROP 2 LAST ROOM DEBUG
J 0
(920 2565);
DISPLAY 1.276596 (920 2565);
PAINT WHITE (920 2565);
DISPLAY INVISIBLE (920 2565);
FORCEADD RES..2
(875 3825);
FORCEPROP 1 LAST LOCATION R4P12
J 0
(920 3950);
DISPLAY 0.617021 (920 3950);
PAINT AQUA (920 3950);
FORCEPROP 1 LAST PART_NUMBER G21796-017
J 0
(915 3700);
DISPLAY 0.617021 (915 3700);
PAINT BLUE (915 3700);
FORCEPROP 1 LAST VALUE 100.0
J 0
(920 3900);
DISPLAY 0.617021 (920 3900);
PAINT SKYBLUE (920 3900);
FORCEPROP 1 LAST TOLERANCE 1%
J 0
(920 3850);
DISPLAY 0.617021 (920 3850);
PAINT SKYBLUE (920 3850);
FORCEPROP 1 LAST PACK_TYPE 0402
J 0
(915 3650);
DISPLAY 0.617021 (915 3650);
PAINT SKYBLUE (915 3650);
FORCEPROP 1 LAST MATERIAL CHIP
J 0
(915 3750);
DISPLAY 0.617021 (915 3750);
PAINT SKYBLUE (915 3750);
FORCEPROP 1 LAST WATTAGE 1/16W
J 0
(915 3800);
DISPLAY 0.617021 (915 3800);
PAINT SKYBLUE (915 3800);
FORCEPROP 1 LASTPIN (875 3725) $PN 2
J 0
(880 3735);
DISPLAY 0.617021 (880 3735);
PAINT ORANGE (880 3735);
FORCEPROP 1 LASTPIN (875 3925) $PN 1
J 0
(880 3887);
DISPLAY 0.617021 (880 3887);
PAINT ORANGE (880 3887);
FORCEPROP 2 LAST CDS_LIB mstr_discrete
J 0
(875 3825);
PAINT MONO (875 3825);
DISPLAY INVISIBLE (875 3825);
FORCEPROP 2 LAST SEC_TYPE 0402
J 0
(925 4050);
DISPLAY 1.021277 (925 4050);
PAINT ORANGE (925 4050);
DISPLAY INVISIBLE (925 4050);
FORCEPROP 2 LAST SEC 1
J 0
(925 4050);
DISPLAY 0.680851 (925 4050);
PAINT MONO (925 4050);
DISPLAY INVISIBLE (925 4050);
FORCEPROP 2 LAST CDS_LOCATION R4P12
J 0
(920 3950);
DISPLAY 0.617021 (920 3950);
PAINT AQUA (920 3950);
DISPLAY INVISIBLE (920 3950);
FORCEPROP 1 LAST PATH I57
J 0
(925 4000);
DISPLAY 0.978723 (925 4000);
PAINT WHITE (925 4000);
DISPLAY INVISIBLE (925 4000);
FORCEPROP 2 LAST ROOM DEBUG
J 0
(920 3990);
DISPLAY 1.276596 (920 3990);
PAINT WHITE (920 3990);
DISPLAY INVISIBLE (920 3990);
FORCEADD RES..2
(575 3800);
FORCEPROP 1 LAST LOCATION R4P23
J 0
(620 3925);
DISPLAY 0.617021 (620 3925);
PAINT AQUA (620 3925);
FORCEPROP 1 LAST PART_NUMBER G21796-009
J 0
(615 3675);
DISPLAY 0.617021 (615 3675);
PAINT BLUE (615 3675);
FORCEPROP 1 LAST VALUE 150.0
J 0
(620 3875);
DISPLAY 0.617021 (620 3875);
PAINT SKYBLUE (620 3875);
FORCEPROP 1 LAST TOLERANCE 1%
J 0
(620 3825);
DISPLAY 0.617021 (620 3825);
PAINT SKYBLUE (620 3825);
FORCEPROP 1 LAST PACK_TYPE 0402
J 0
(615 3625);
DISPLAY 0.617021 (615 3625);
PAINT SKYBLUE (615 3625);
FORCEPROP 1 LAST MATERIAL CHIP
J 0
(615 3725);
DISPLAY 0.617021 (615 3725);
PAINT SKYBLUE (615 3725);
FORCEPROP 1 LAST WATTAGE 1/16W
J 0
(615 3775);
DISPLAY 0.617021 (615 3775);
PAINT SKYBLUE (615 3775);
FORCEPROP 1 LASTPIN (575 3700) $PN 2
J 0
(580 3710);
DISPLAY 0.617021 (580 3710);
PAINT ORANGE (580 3710);
FORCEPROP 1 LASTPIN (575 3900) $PN 1
J 0
(580 3862);
DISPLAY 0.617021 (580 3862);
PAINT ORANGE (580 3862);
FORCEPROP 2 LAST SEC_TYPE 0402
J 0
(625 4025);
DISPLAY 1.021277 (625 4025);
PAINT ORANGE (625 4025);
DISPLAY INVISIBLE (625 4025);
FORCEPROP 2 LAST CDS_LIB mstr_discrete
J 0
(575 3800);
PAINT ORANGE (575 3800);
DISPLAY INVISIBLE (575 3800);
FORCEPROP 2 LAST SEC 1
J 0
(625 4025);
DISPLAY 0.680851 (625 4025);
PAINT MONO (625 4025);
DISPLAY INVISIBLE (625 4025);
FORCEPROP 2 LAST CDS_LOCATION R4P23
J 0
(620 3925);
DISPLAY 0.617021 (620 3925);
PAINT AQUA (620 3925);
DISPLAY INVISIBLE (620 3925);
FORCEPROP 1 LAST PATH I58
J 0
(625 3975);
DISPLAY 0.978723 (625 3975);
PAINT WHITE (625 3975);
DISPLAY INVISIBLE (625 3975);
FORCEPROP 2 LAST ROOM DEBUG
J 0
(620 3965);
DISPLAY 1.276596 (620 3965);
PAINT WHITE (620 3965);
DISPLAY INVISIBLE (620 3965);
FORCEADD RES..2
(275 3800);
FORCEPROP 1 LAST LOCATION R4P24
J 0
(320 3925);
DISPLAY 0.617021 (320 3925);
PAINT AQUA (320 3925);
FORCEPROP 1 LAST PART_NUMBER G21796-009
J 0
(315 3675);
DISPLAY 0.617021 (315 3675);
PAINT BLUE (315 3675);
FORCEPROP 1 LAST VALUE 150.0
J 0
(320 3875);
DISPLAY 0.617021 (320 3875);
PAINT SKYBLUE (320 3875);
FORCEPROP 1 LAST TOLERANCE 1%
J 0
(320 3825);
DISPLAY 0.617021 (320 3825);
PAINT SKYBLUE (320 3825);
FORCEPROP 1 LAST PACK_TYPE 0402
J 0
(315 3625);
DISPLAY 0.617021 (315 3625);
PAINT SKYBLUE (315 3625);
FORCEPROP 1 LAST MATERIAL CHIP
J 0
(315 3725);
DISPLAY 0.617021 (315 3725);
PAINT SKYBLUE (315 3725);
FORCEPROP 1 LAST WATTAGE 1/16W
J 0
(315 3775);
DISPLAY 0.617021 (315 3775);
PAINT SKYBLUE (315 3775);
FORCEPROP 1 LASTPIN (275 3700) $PN 2
J 0
(280 3710);
DISPLAY 0.617021 (280 3710);
PAINT ORANGE (280 3710);
FORCEPROP 1 LASTPIN (275 3900) $PN 1
J 0
(280 3862);
DISPLAY 0.617021 (280 3862);
PAINT ORANGE (280 3862);
FORCEPROP 2 LAST CDS_LIB mstr_discrete
J 0
(275 3800);
PAINT ORANGE (275 3800);
DISPLAY INVISIBLE (275 3800);
FORCEPROP 2 LAST SEC_TYPE 0402
J 0
(325 4025);
DISPLAY 1.021277 (325 4025);
PAINT ORANGE (325 4025);
DISPLAY INVISIBLE (325 4025);
FORCEPROP 2 LAST SEC 1
J 0
(325 4025);
DISPLAY 0.680851 (325 4025);
PAINT MONO (325 4025);
DISPLAY INVISIBLE (325 4025);
FORCEPROP 2 LAST CDS_LOCATION R4P24
J 0
(320 3925);
DISPLAY 0.617021 (320 3925);
PAINT AQUA (320 3925);
DISPLAY INVISIBLE (320 3925);
FORCEPROP 1 LAST PATH I59
J 0
(325 3975);
DISPLAY 0.978723 (325 3975);
PAINT WHITE (325 3975);
DISPLAY INVISIBLE (325 3975);
FORCEPROP 2 LAST ROOM DEBUG
J 0
(320 3965);
DISPLAY 1.276596 (320 3965);
PAINT WHITE (320 3965);
DISPLAY INVISIBLE (320 3965);
FORCEADD RES..2
(500 2400);
FORCEPROP 1 LAST LOCATION R1L15
J 0
(545 2525);
DISPLAY 0.617021 (545 2525);
PAINT AQUA (545 2525);
FORCEPROP 1 LAST PART_NUMBER G21796-009
J 0
(540 2275);
DISPLAY 0.617021 (540 2275);
PAINT BLUE (540 2275);
FORCEPROP 1 LAST VALUE 150.0
J 0
(545 2475);
DISPLAY 0.617021 (545 2475);
PAINT SKYBLUE (545 2475);
FORCEPROP 1 LAST TOLERANCE 1%
J 0
(545 2425);
DISPLAY 0.617021 (545 2425);
PAINT SKYBLUE (545 2425);
FORCEPROP 1 LAST PACK_TYPE 0402
J 0
(540 2225);
DISPLAY 0.617021 (540 2225);
PAINT SKYBLUE (540 2225);
FORCEPROP 1 LAST MATERIAL CHIP
J 0
(540 2325);
DISPLAY 0.617021 (540 2325);
PAINT SKYBLUE (540 2325);
FORCEPROP 1 LAST WATTAGE 1/16W
J 0
(540 2375);
DISPLAY 0.617021 (540 2375);
PAINT SKYBLUE (540 2375);
FORCEPROP 1 LASTPIN (500 2300) $PN 2
J 0
(505 2310);
DISPLAY 0.617021 (505 2310);
PAINT ORANGE (505 2310);
FORCEPROP 1 LASTPIN (500 2500) $PN 1
J 0
(505 2462);
DISPLAY 0.617021 (505 2462);
PAINT ORANGE (505 2462);
FORCEPROP 2 LAST SEC_TYPE 0402
J 0
(550 2625);
DISPLAY 1.021277 (550 2625);
PAINT ORANGE (550 2625);
DISPLAY INVISIBLE (550 2625);
FORCEPROP 2 LAST CDS_LIB mstr_discrete
J 0
(500 2400);
PAINT MONO (500 2400);
DISPLAY INVISIBLE (500 2400);
FORCEPROP 2 LAST SEC 1
J 0
(550 2625);
DISPLAY 0.680851 (550 2625);
PAINT MONO (550 2625);
DISPLAY INVISIBLE (550 2625);
FORCEPROP 2 LAST CDS_LOCATION R1L15
J 0
(545 2525);
DISPLAY 0.617021 (545 2525);
PAINT AQUA (545 2525);
DISPLAY INVISIBLE (545 2525);
FORCEPROP 1 LAST PATH I60
J 0
(550 2575);
DISPLAY 0.978723 (550 2575);
PAINT WHITE (550 2575);
DISPLAY INVISIBLE (550 2575);
FORCEPROP 2 LAST ROOM DEBUG
J 0
(545 2565);
DISPLAY 1.276596 (545 2565);
PAINT WHITE (545 2565);
DISPLAY INVISIBLE (545 2565);
FORCEADD RES..2
(875 1100);
FORCEPROP 1 LAST LOCATION R7P29
J 0
(920 1225);
DISPLAY 0.617021 (920 1225);
PAINT AQUA (920 1225);
FORCEPROP 1 LAST PART_NUMBER G21796-208
J 0
(915 975);
DISPLAY 0.617021 (915 975);
PAINT BLUE (915 975);
FORCEPROP 1 LAST VALUE 51.1
J 0
(920 1175);
DISPLAY 0.617021 (920 1175);
PAINT SKYBLUE (920 1175);
FORCEPROP 1 LAST TOLERANCE 1.0%
J 0
(920 1125);
DISPLAY 0.617021 (920 1125);
PAINT SKYBLUE (920 1125);
FORCEPROP 1 LAST PACK_TYPE 0402
J 0
(915 925);
DISPLAY 0.617021 (915 925);
PAINT SKYBLUE (915 925);
FORCEPROP 1 LAST MATERIAL CHIP
J 0
(915 1025);
DISPLAY 0.617021 (915 1025);
PAINT SKYBLUE (915 1025);
FORCEPROP 1 LAST WATTAGE 1/16W
J 0
(915 1075);
DISPLAY 0.617021 (915 1075);
PAINT SKYBLUE (915 1075);
FORCEPROP 1 LASTPIN (875 1000) $PN 2
J 0
(880 1010);
DISPLAY 0.617021 (880 1010);
PAINT WHITE (880 1010);
FORCEPROP 1 LASTPIN (875 1200) $PN 1
J 0
(880 1162);
DISPLAY 0.617021 (880 1162);
PAINT WHITE (880 1162);
FORCEPROP 2 LAST CDS_LIB mstr_discrete
J 0
(875 1100);
DISPLAY 2.212766 (875 1100);
PAINT ORANGE (875 1100);
DISPLAY INVISIBLE (875 1100);
FORCEPROP 2 LAST BOM_COST DEBUG
J 0
(925 1275);
DISPLAY 1.617021 (925 1275);
PAINT WHITE (925 1275);
DISPLAY INVISIBLE (925 1275);
FORCEPROP 2 LAST CDS_SEC 1
J 0
(925 1325);
PAINT MONO (925 1325);
DISPLAY INVISIBLE (925 1325);
FORCEPROP 2 LAST $SEC 1
J 0
(925 1325);
PAINT MONO (925 1325);
DISPLAY INVISIBLE (925 1325);
FORCEPROP 2 LAST CDS_LOCATION R7P29
J 0
(920 1225);
DISPLAY 0.617021 (920 1225);
PAINT AQUA (920 1225);
DISPLAY INVISIBLE (920 1225);
FORCEPROP 1 LAST PATH I61
J 0
(925 1275);
DISPLAY 0.978723 (925 1275);
PAINT WHITE (925 1275);
DISPLAY INVISIBLE (925 1275);
FORCEPROP 2 LAST ROOM DEBUG
J 0
(925 1275);
DISPLAY 1.617021 (925 1275);
PAINT WHITE (925 1275);
DISPLAY INVISIBLE (925 1275);
FORCEADD RES..2
(500 1100);
FORCEPROP 1 LAST LOCATION R6T5
J 0
(545 1225);
DISPLAY 0.617021 (545 1225);
PAINT AQUA (545 1225);
FORCEPROP 1 LAST PART_NUMBER G21796-026
J 0
(540 975);
DISPLAY 0.617021 (540 975);
PAINT BLUE (540 975);
FORCEPROP 1 LAST VALUE 1.00K
J 0
(545 1175);
DISPLAY 0.617021 (545 1175);
PAINT SKYBLUE (545 1175);
FORCEPROP 1 LAST TOLERANCE 1%
J 0
(545 1125);
DISPLAY 0.617021 (545 1125);
PAINT SKYBLUE (545 1125);
FORCEPROP 1 LAST PACK_TYPE 0402
J 0
(540 925);
DISPLAY 0.617021 (540 925);
PAINT SKYBLUE (540 925);
FORCEPROP 1 LAST MATERIAL CHIP
J 0
(540 1025);
DISPLAY 0.617021 (540 1025);
PAINT SKYBLUE (540 1025);
FORCEPROP 1 LAST WATTAGE 1/16W
J 0
(540 1075);
DISPLAY 0.617021 (540 1075);
PAINT SKYBLUE (540 1075);
FORCEPROP 1 LASTPIN (500 1000) $PN 2
J 0
(505 1010);
DISPLAY 0.617021 (505 1010);
PAINT ORANGE (505 1010);
FORCEPROP 1 LASTPIN (500 1200) $PN 1
J 0
(505 1162);
DISPLAY 0.617021 (505 1162);
PAINT ORANGE (505 1162);
FORCEPROP 2 LAST BOM_COST DEBUG
J 0
(550 1275);
DISPLAY 1.617021 (550 1275);
PAINT WHITE (550 1275);
DISPLAY INVISIBLE (550 1275);
FORCEPROP 2 LAST CDS_LIB mstr_discrete
J 0
(500 1100);
PAINT MONO (500 1100);
DISPLAY INVISIBLE (500 1100);
FORCEPROP 2 LAST SEC_TYPE 0402
J 0
(550 1325);
DISPLAY 1.021277 (550 1325);
PAINT ORANGE (550 1325);
DISPLAY INVISIBLE (550 1325);
FORCEPROP 2 LAST SEC 1
J 0
(550 1325);
DISPLAY 0.680851 (550 1325);
PAINT MONO (550 1325);
DISPLAY INVISIBLE (550 1325);
FORCEPROP 2 LAST CDS_LOCATION R6T5
J 0
(545 1225);
DISPLAY 0.617021 (545 1225);
PAINT AQUA (545 1225);
DISPLAY INVISIBLE (545 1225);
FORCEPROP 1 LAST PATH I62
J 0
(550 1275);
DISPLAY 0.978723 (550 1275);
PAINT WHITE (550 1275);
DISPLAY INVISIBLE (550 1275);
FORCEPROP 2 LAST ROOM DEBUG
J 0
(550 1275);
DISPLAY 1.617021 (550 1275);
PAINT WHITE (550 1275);
DISPLAY INVISIBLE (550 1275);
FORCEADD OFFPAGE..1
(-100 2250);
FORCEPROP 2 LAST $XR0 112 
J 0
(-352 2250);
DISPLAY 0.638298 (-352 2250);
PAINT MONO (-352 2250);
FORCEPROP 2 LAST $XR1 21 
J 0
(-442 2250);
DISPLAY 0.638298 (-442 2250);
PAINT MONO (-442 2250);
FORCEPROP 2 LAST $XR2 55 
J 0
(-532 2250);
DISPLAY 0.638298 (-532 2250);
PAINT MONO (-532 2250);
FORCEPROP 2 LAST CDS_LIB mstr_standard
J 0
(-100 2250);
DISPLAY 2.212766 (-100 2250);
PAINT ORANGE (-100 2250);
DISPLAY INVISIBLE (-100 2250);
FORCEPROP 1 LAST OFFPAGE TRUE
J 0
(225 2125);
DISPLAY 1.404255 (225 2125);
PAINT GREEN (225 2125);
DISPLAY INVISIBLE (225 2125);
FORCEPROP 1 LAST COMMENT_BODY TRUE
J 0
(25 2150);
DISPLAY 1.404255 (25 2150);
PAINT PEACH (25 2150);
DISPLAY INVISIBLE (25 2150);
FORCEPROP 2 LAST PATH I63
J 0
(-350 2300);
DISPLAY 1.021277 (-350 2300);
PAINT ORANGE (-350 2300);
DISPLAY INVISIBLE (-350 2300);
FORCEADD OFFPAGE..1
(-100 2175);
FORCEPROP 2 LAST $XR0 112 
J 0
(-352 2175);
DISPLAY 0.638298 (-352 2175);
PAINT MONO (-352 2175);
FORCEPROP 2 LAST $XR1 55 
J 0
(-442 2175);
DISPLAY 0.638298 (-442 2175);
PAINT MONO (-442 2175);
FORCEPROP 2 LAST CDS_LIB mstr_standard
J 0
(-100 2175);
DISPLAY 2.212766 (-100 2175);
PAINT ORANGE (-100 2175);
DISPLAY INVISIBLE (-100 2175);
FORCEPROP 1 LAST OFFPAGE TRUE
J 0
(225 2050);
DISPLAY 1.404255 (225 2050);
PAINT GREEN (225 2050);
DISPLAY INVISIBLE (225 2050);
FORCEPROP 1 LAST COMMENT_BODY TRUE
J 0
(25 2075);
DISPLAY 1.404255 (25 2075);
PAINT PEACH (25 2075);
DISPLAY INVISIBLE (25 2075);
FORCEPROP 2 LAST PATH I64
J 0
(-350 2225);
DISPLAY 1.021277 (-350 2225);
PAINT ORANGE (-350 2225);
DISPLAY INVISIBLE (-350 2225);
FORCEADD OFFPAGE..1
(-100 2100);
FORCEPROP 2 LAST $XR0 55 
J 0
(-321 2100);
DISPLAY 0.638298 (-321 2100);
PAINT MONO (-321 2100);
FORCEPROP 2 LAST $XR1 112 
J 0
(-441 2100);
DISPLAY 0.638298 (-441 2100);
PAINT MONO (-441 2100);
FORCEPROP 2 LAST CDS_LIB mstr_standard
J 0
(-100 2100);
DISPLAY 2.212766 (-100 2100);
PAINT ORANGE (-100 2100);
DISPLAY INVISIBLE (-100 2100);
FORCEPROP 1 LAST OFFPAGE TRUE
J 0
(225 1975);
DISPLAY 1.404255 (225 1975);
PAINT GREEN (225 1975);
DISPLAY INVISIBLE (225 1975);
FORCEPROP 1 LAST COMMENT_BODY TRUE
J 0
(25 2000);
DISPLAY 1.404255 (25 2000);
PAINT PEACH (25 2000);
DISPLAY INVISIBLE (25 2000);
FORCEPROP 2 LAST PATH I65
J 0
(-300 2150);
DISPLAY 1.021277 (-300 2150);
PAINT ORANGE (-300 2150);
DISPLAY INVISIBLE (-300 2150);
FORCEADD OFFPAGE..1
(-100 2025);
FORCEPROP 2 LAST $XR0 112 
J 0
(-352 2025);
DISPLAY 0.638298 (-352 2025);
PAINT MONO (-352 2025);
FORCEPROP 2 LAST $XR1 21 
J 0
(-442 2025);
DISPLAY 0.638298 (-442 2025);
PAINT MONO (-442 2025);
FORCEPROP 2 LAST $XR2 55 
J 0
(-532 2025);
DISPLAY 0.638298 (-532 2025);
PAINT MONO (-532 2025);
FORCEPROP 2 LAST CDS_LIB mstr_standard
J 0
(-100 2025);
DISPLAY 2.212766 (-100 2025);
PAINT ORANGE (-100 2025);
DISPLAY INVISIBLE (-100 2025);
FORCEPROP 1 LAST OFFPAGE TRUE
J 0
(225 1900);
DISPLAY 1.404255 (225 1900);
PAINT GREEN (225 1900);
DISPLAY INVISIBLE (225 1900);
FORCEPROP 1 LAST COMMENT_BODY TRUE
J 0
(25 1925);
DISPLAY 1.404255 (25 1925);
PAINT PEACH (25 1925);
DISPLAY INVISIBLE (25 1925);
FORCEPROP 2 LAST PATH I66
J 0
(-350 2075);
DISPLAY 1.021277 (-350 2075);
PAINT ORANGE (-350 2075);
DISPLAY INVISIBLE (-350 2075);
FORCEADD OFFPAGE..1
(-100 1950);
FORCEPROP 2 LAST $XR0 21 
J 0
(-321 1950);
DISPLAY 0.638298 (-321 1950);
PAINT MONO (-321 1950);
FORCEPROP 2 LAST $XR1 55 
J 0
(-411 1950);
DISPLAY 0.638298 (-411 1950);
PAINT MONO (-411 1950);
FORCEPROP 2 LAST $XR2 112 
J 0
(-531 1950);
DISPLAY 0.638298 (-531 1950);
PAINT MONO (-531 1950);
FORCEPROP 2 LAST CDS_LIB mstr_standard
J 0
(-100 1950);
DISPLAY 2.212766 (-100 1950);
PAINT ORANGE (-100 1950);
DISPLAY INVISIBLE (-100 1950);
FORCEPROP 1 LAST OFFPAGE TRUE
J 0
(225 1825);
DISPLAY 1.404255 (225 1825);
PAINT GREEN (225 1825);
DISPLAY INVISIBLE (225 1825);
FORCEPROP 1 LAST COMMENT_BODY TRUE
J 0
(25 1850);
DISPLAY 1.404255 (25 1850);
PAINT PEACH (25 1850);
DISPLAY INVISIBLE (25 1850);
FORCEPROP 2 LAST PATH I67
J 0
(-275 2000);
DISPLAY 1.021277 (-275 2000);
PAINT ORANGE (-275 2000);
DISPLAY INVISIBLE (-275 2000);
FORCEADD OFFPAGE..1
(-100 1875);
FORCEPROP 2 LAST $XR0 21 
J 0
(-321 1875);
DISPLAY 0.638298 (-321 1875);
PAINT MONO (-321 1875);
FORCEPROP 2 LAST $XR1 55 
J 0
(-411 1875);
DISPLAY 0.638298 (-411 1875);
PAINT MONO (-411 1875);
FORCEPROP 2 LAST $XR2 112 
J 0
(-531 1875);
DISPLAY 0.638298 (-531 1875);
PAINT MONO (-531 1875);
FORCEPROP 2 LAST CDS_LIB mstr_standard
J 0
(-100 1875);
DISPLAY 2.212766 (-100 1875);
PAINT ORANGE (-100 1875);
DISPLAY INVISIBLE (-100 1875);
FORCEPROP 1 LAST OFFPAGE TRUE
J 0
(225 1750);
DISPLAY 1.404255 (225 1750);
PAINT GREEN (225 1750);
DISPLAY INVISIBLE (225 1750);
FORCEPROP 1 LAST COMMENT_BODY TRUE
J 0
(25 1775);
DISPLAY 1.404255 (25 1775);
PAINT PEACH (25 1775);
DISPLAY INVISIBLE (25 1775);
FORCEPROP 2 LAST PATH I68
J 0
(-275 1925);
DISPLAY 1.021277 (-275 1925);
PAINT ORANGE (-275 1925);
DISPLAY INVISIBLE (-275 1925);
FORCEADD OFFPAGE..1
(-100 1800);
FORCEPROP 2 LAST $XR0 21 
J 0
(-321 1800);
DISPLAY 0.638298 (-321 1800);
PAINT MONO (-321 1800);
FORCEPROP 2 LAST $XR1 55 
J 0
(-411 1800);
DISPLAY 0.638298 (-411 1800);
PAINT MONO (-411 1800);
FORCEPROP 2 LAST $XR2 112 
J 0
(-531 1800);
DISPLAY 0.638298 (-531 1800);
PAINT MONO (-531 1800);
FORCEPROP 2 LAST CDS_LIB mstr_standard
J 0
(-100 1800);
DISPLAY 2.212766 (-100 1800);
PAINT ORANGE (-100 1800);
DISPLAY INVISIBLE (-100 1800);
FORCEPROP 1 LAST OFFPAGE TRUE
J 0
(225 1675);
DISPLAY 1.404255 (225 1675);
PAINT GREEN (225 1675);
DISPLAY INVISIBLE (225 1675);
FORCEPROP 1 LAST COMMENT_BODY TRUE
J 0
(25 1700);
DISPLAY 1.404255 (25 1700);
PAINT PEACH (25 1700);
DISPLAY INVISIBLE (25 1700);
FORCEPROP 2 LAST PATH I69
J 0
(-275 1850);
DISPLAY 1.021277 (-275 1850);
PAINT ORANGE (-275 1850);
DISPLAY INVISIBLE (-275 1850);
FORCEADD OFFPAGE..1
(-100 1575);
FORCEPROP 2 LAST $XR0 21 
J 0
(-321 1575);
DISPLAY 0.638298 (-321 1575);
PAINT MONO (-321 1575);
FORCEPROP 2 LAST $XR1 55 
J 0
(-411 1575);
DISPLAY 0.638298 (-411 1575);
PAINT MONO (-411 1575);
FORCEPROP 2 LAST $XR2 112 
J 0
(-531 1575);
DISPLAY 0.638298 (-531 1575);
PAINT MONO (-531 1575);
FORCEPROP 2 LAST CDS_LIB mstr_standard
J 0
(-100 1575);
DISPLAY 2.212766 (-100 1575);
PAINT ORANGE (-100 1575);
DISPLAY INVISIBLE (-100 1575);
FORCEPROP 1 LAST OFFPAGE TRUE
J 0
(225 1450);
DISPLAY 1.404255 (225 1450);
PAINT GREEN (225 1450);
DISPLAY INVISIBLE (225 1450);
FORCEPROP 1 LAST COMMENT_BODY TRUE
J 0
(25 1475);
DISPLAY 1.404255 (25 1475);
PAINT PEACH (25 1475);
DISPLAY INVISIBLE (25 1475);
FORCEPROP 2 LAST PATH I70
J 0
(-350 1625);
DISPLAY 1.021277 (-350 1625);
PAINT ORANGE (-350 1625);
DISPLAY INVISIBLE (-350 1625);
FORCEADD OFFPAGE..1
(-100 1425);
FORCEPROP 2 LAST $XR0 111 
J 0
(-352 1425);
DISPLAY 0.638298 (-352 1425);
PAINT MONO (-352 1425);
FORCEPROP 2 LAST $XR1 21 
J 0
(-442 1425);
DISPLAY 0.638298 (-442 1425);
PAINT MONO (-442 1425);
FORCEPROP 2 LAST $XR2 55 
J 0
(-532 1425);
DISPLAY 0.638298 (-532 1425);
PAINT MONO (-532 1425);
FORCEPROP 2 LAST CDS_LIB mstr_standard
J 0
(-100 1425);
DISPLAY 2.212766 (-100 1425);
PAINT ORANGE (-100 1425);
DISPLAY INVISIBLE (-100 1425);
FORCEPROP 1 LAST OFFPAGE TRUE
J 0
(225 1300);
DISPLAY 1.404255 (225 1300);
PAINT GREEN (225 1300);
DISPLAY INVISIBLE (225 1300);
FORCEPROP 1 LAST COMMENT_BODY TRUE
J 0
(25 1325);
DISPLAY 1.404255 (25 1325);
PAINT PEACH (25 1325);
DISPLAY INVISIBLE (25 1325);
FORCEPROP 2 LAST PATH I71
J 0
(-350 1475);
DISPLAY 1.021277 (-350 1475);
PAINT ORANGE (-350 1475);
DISPLAY INVISIBLE (-350 1475);
FORCEADD OFFPAGE..1
(-100 1500);
FORCEPROP 2 LAST $XR0 21 
J 0
(-321 1500);
DISPLAY 0.638298 (-321 1500);
PAINT MONO (-321 1500);
FORCEPROP 2 LAST $XR1 55 
J 0
(-411 1500);
DISPLAY 0.638298 (-411 1500);
PAINT MONO (-411 1500);
FORCEPROP 2 LAST $XR2 112 
J 0
(-531 1500);
DISPLAY 0.638298 (-531 1500);
PAINT MONO (-531 1500);
FORCEPROP 2 LAST CDS_LIB mstr_standard
J 0
(-100 1500);
DISPLAY 2.212766 (-100 1500);
PAINT ORANGE (-100 1500);
DISPLAY INVISIBLE (-100 1500);
FORCEPROP 1 LAST OFFPAGE TRUE
J 0
(225 1375);
DISPLAY 1.404255 (225 1375);
PAINT GREEN (225 1375);
DISPLAY INVISIBLE (225 1375);
FORCEPROP 1 LAST COMMENT_BODY TRUE
J 0
(25 1400);
DISPLAY 1.404255 (25 1400);
PAINT PEACH (25 1400);
DISPLAY INVISIBLE (25 1400);
FORCEPROP 2 LAST PATH I72
J 0
(-350 1550);
DISPLAY 1.021277 (-350 1550);
PAINT ORANGE (-350 1550);
DISPLAY INVISIBLE (-350 1550);
FORCEADD OFFPAGE..1
(-100 1350);
FORCEPROP 2 LAST $XR0 112 
J 0
(-352 1350);
DISPLAY 0.638298 (-352 1350);
PAINT MONO (-352 1350);
FORCEPROP 2 LAST $XR1 21 
J 0
(-442 1350);
DISPLAY 0.638298 (-442 1350);
PAINT MONO (-442 1350);
FORCEPROP 2 LAST $XR2 55 
J 0
(-532 1350);
DISPLAY 0.638298 (-532 1350);
PAINT MONO (-532 1350);
FORCEPROP 2 LAST CDS_LIB mstr_standard
J 0
(-100 1350);
DISPLAY 2.212766 (-100 1350);
PAINT ORANGE (-100 1350);
DISPLAY INVISIBLE (-100 1350);
FORCEPROP 1 LAST OFFPAGE TRUE
J 0
(225 1225);
DISPLAY 1.404255 (225 1225);
PAINT GREEN (225 1225);
DISPLAY INVISIBLE (225 1225);
FORCEPROP 1 LAST COMMENT_BODY TRUE
J 0
(25 1250);
DISPLAY 1.404255 (25 1250);
PAINT PEACH (25 1250);
DISPLAY INVISIBLE (25 1250);
FORCEPROP 2 LAST PATH I73
J 0
(-350 1400);
DISPLAY 1.021277 (-350 1400);
PAINT ORANGE (-350 1400);
DISPLAY INVISIBLE (-350 1400);
FORCEADD GND..1
(500 725);
FORCEPROP 3 LASTPIN (500 775) SIG_NAME GND\g
J 0
(510 785);
DISPLAY 0.659574 (510 785);
PAINT MONO (510 785);
DISPLAY INVISIBLE (510 785);
FORCEPROP 1 LAST VOLTAGE 0.0V
J 0
(455 682);
DISPLAY 0.340426 (455 682);
PAINT SKYBLUE (455 682);
DISPLAY INVISIBLE (455 682);
FORCEPROP 1 LAST SIZE 1B
J 0
(575 675);
DISPLAY 2.382979 (575 675);
PAINT GREEN (575 675);
DISPLAY INVISIBLE (575 675);
FORCEPROP 2 LAST CDS_LIB mstr_symbols
J 0
(500 725);
DISPLAY 2.212766 (500 725);
PAINT ORANGE (500 725);
DISPLAY INVISIBLE (500 725);
FORCEPROP 1 LAST BODY_TYPE PLUMBING
J 0
(455 682);
DISPLAY 0.340426 (455 682);
PAINT GREEN (455 682);
DISPLAY INVISIBLE (455 682);
FORCEPROP 1 LAST PATH I74
J 0
(575 725);
DISPLAY 0.872340 (575 725);
PAINT AQUA (575 725);
DISPLAY INVISIBLE (575 725);
FORCEPROP 1 LAST HDL_POWER GND
J 0
(500 875);
PAINT GREEN (500 875);
DISPLAY INVISIBLE (500 875);
FORCEADD RES..2
(-1200 4425);
FORCEPROP 1 LAST LOCATION R1L39
J 0
(-1155 4550);
DISPLAY 0.617021 (-1155 4550);
PAINT AQUA (-1155 4550);
FORCEPROP 1 LAST PART_NUMBER G21796-017
J 0
(-1160 4300);
DISPLAY 0.617021 (-1160 4300);
PAINT BLUE (-1160 4300);
FORCEPROP 1 LAST VALUE 100.0
J 0
(-1155 4500);
DISPLAY 0.617021 (-1155 4500);
PAINT SKYBLUE (-1155 4500);
FORCEPROP 1 LAST TOLERANCE 1%
J 0
(-1155 4450);
DISPLAY 0.617021 (-1155 4450);
PAINT SKYBLUE (-1155 4450);
FORCEPROP 1 LAST PACK_TYPE 0402
J 0
(-1160 4250);
DISPLAY 0.617021 (-1160 4250);
PAINT SKYBLUE (-1160 4250);
FORCEPROP 1 LAST MATERIAL CHIP
J 0
(-1160 4350);
DISPLAY 0.617021 (-1160 4350);
PAINT SKYBLUE (-1160 4350);
FORCEPROP 1 LAST WATTAGE 1/16W
J 0
(-1160 4400);
DISPLAY 0.617021 (-1160 4400);
PAINT SKYBLUE (-1160 4400);
FORCEPROP 1 LASTPIN (-1200 4325) $PN 2
J 0
(-1195 4335);
DISPLAY 0.617021 (-1195 4335);
PAINT ORANGE (-1195 4335);
FORCEPROP 1 LASTPIN (-1200 4525) $PN 1
J 0
(-1195 4487);
DISPLAY 0.617021 (-1195 4487);
PAINT ORANGE (-1195 4487);
FORCEPROP 2 LAST CDS_LIB mstr_discrete
J 0
(-1200 4425);
PAINT ORANGE (-1200 4425);
DISPLAY INVISIBLE (-1200 4425);
FORCEPROP 2 LAST SEC_TYPE 0402
J 0
(-1150 4650);
DISPLAY 1.021277 (-1150 4650);
PAINT ORANGE (-1150 4650);
DISPLAY INVISIBLE (-1150 4650);
FORCEPROP 2 LAST SEC 1
J 0
(-1150 4650);
DISPLAY 0.680851 (-1150 4650);
PAINT MONO (-1150 4650);
DISPLAY INVISIBLE (-1150 4650);
FORCEPROP 2 LAST CDS_LOCATION R1L39
J 0
(-1155 4550);
DISPLAY 0.617021 (-1155 4550);
PAINT AQUA (-1155 4550);
DISPLAY INVISIBLE (-1155 4550);
FORCEPROP 1 LAST PATH I76
J 0
(-1150 4600);
DISPLAY 0.978723 (-1150 4600);
PAINT WHITE (-1150 4600);
DISPLAY INVISIBLE (-1150 4600);
FORCEPROP 2 LAST ROOM DEBUG
J 0
(-1155 4590);
DISPLAY 1.276596 (-1155 4590);
PAINT WHITE (-1155 4590);
DISPLAY INVISIBLE (-1155 4590);
FORCEADD RES..2
(-1575 4425);
FORCEPROP 1 LAST LOCATION R1L41
J 0
(-1530 4550);
DISPLAY 0.617021 (-1530 4550);
PAINT AQUA (-1530 4550);
FORCEPROP 1 LAST PART_NUMBER G21796-017
J 0
(-1535 4300);
DISPLAY 0.617021 (-1535 4300);
PAINT BLUE (-1535 4300);
FORCEPROP 1 LAST VALUE 100.0
J 0
(-1530 4500);
DISPLAY 0.617021 (-1530 4500);
PAINT SKYBLUE (-1530 4500);
FORCEPROP 1 LAST TOLERANCE 1%
J 0
(-1530 4450);
DISPLAY 0.617021 (-1530 4450);
PAINT SKYBLUE (-1530 4450);
FORCEPROP 1 LAST PACK_TYPE 0402
J 0
(-1535 4250);
DISPLAY 0.617021 (-1535 4250);
PAINT SKYBLUE (-1535 4250);
FORCEPROP 1 LAST MATERIAL CHIP
J 0
(-1535 4350);
DISPLAY 0.617021 (-1535 4350);
PAINT SKYBLUE (-1535 4350);
FORCEPROP 1 LAST WATTAGE 1/16W
J 0
(-1535 4400);
DISPLAY 0.617021 (-1535 4400);
PAINT SKYBLUE (-1535 4400);
FORCEPROP 1 LASTPIN (-1575 4325) $PN 2
J 0
(-1570 4335);
DISPLAY 0.617021 (-1570 4335);
PAINT ORANGE (-1570 4335);
FORCEPROP 1 LASTPIN (-1575 4525) $PN 1
J 0
(-1570 4487);
DISPLAY 0.617021 (-1570 4487);
PAINT ORANGE (-1570 4487);
FORCEPROP 2 LAST SEC_TYPE 0402
J 0
(-1525 4650);
DISPLAY 1.021277 (-1525 4650);
PAINT ORANGE (-1525 4650);
DISPLAY INVISIBLE (-1525 4650);
FORCEPROP 2 LAST CDS_LIB mstr_discrete
J 0
(-1575 4425);
PAINT ORANGE (-1575 4425);
DISPLAY INVISIBLE (-1575 4425);
FORCEPROP 2 LAST SEC 1
J 0
(-1525 4650);
DISPLAY 0.680851 (-1525 4650);
PAINT MONO (-1525 4650);
DISPLAY INVISIBLE (-1525 4650);
FORCEPROP 2 LAST CDS_LOCATION R1L41
J 0
(-1530 4550);
DISPLAY 0.617021 (-1530 4550);
PAINT AQUA (-1530 4550);
DISPLAY INVISIBLE (-1530 4550);
FORCEPROP 1 LAST PATH I77
J 0
(-1525 4600);
DISPLAY 0.978723 (-1525 4600);
PAINT WHITE (-1525 4600);
DISPLAY INVISIBLE (-1525 4600);
FORCEPROP 2 LAST ROOM DEBUG
J 0
(-1530 4590);
DISPLAY 1.276596 (-1530 4590);
PAINT WHITE (-1530 4590);
DISPLAY INVISIBLE (-1530 4590);
FORCEADD RES..2
(-1950 4425);
FORCEPROP 1 LAST LOCATION R9A11
J 0
(-1905 4550);
DISPLAY 0.617021 (-1905 4550);
PAINT AQUA (-1905 4550);
FORCEPROP 1 LAST PART_NUMBER G21796-009
J 0
(-1910 4300);
DISPLAY 0.617021 (-1910 4300);
PAINT BLUE (-1910 4300);
FORCEPROP 1 LAST VALUE 150.0
J 0
(-1905 4500);
DISPLAY 0.617021 (-1905 4500);
PAINT SKYBLUE (-1905 4500);
FORCEPROP 1 LAST TOLERANCE 1%
J 0
(-1905 4450);
DISPLAY 0.617021 (-1905 4450);
PAINT SKYBLUE (-1905 4450);
FORCEPROP 1 LAST PACK_TYPE 0402
J 0
(-1910 4250);
DISPLAY 0.617021 (-1910 4250);
PAINT SKYBLUE (-1910 4250);
FORCEPROP 1 LAST MATERIAL CHIP
J 0
(-1910 4350);
DISPLAY 0.617021 (-1910 4350);
PAINT SKYBLUE (-1910 4350);
FORCEPROP 1 LAST WATTAGE 1/16W
J 0
(-1910 4400);
DISPLAY 0.617021 (-1910 4400);
PAINT SKYBLUE (-1910 4400);
FORCEPROP 1 LASTPIN (-1950 4325) $PN 2
J 0
(-1945 4335);
DISPLAY 0.617021 (-1945 4335);
PAINT ORANGE (-1945 4335);
FORCEPROP 1 LASTPIN (-1950 4525) $PN 1
J 0
(-1945 4487);
DISPLAY 0.617021 (-1945 4487);
PAINT ORANGE (-1945 4487);
FORCEPROP 2 LAST CDS_LIB mstr_discrete
J 0
(-1950 4425);
PAINT ORANGE (-1950 4425);
DISPLAY INVISIBLE (-1950 4425);
FORCEPROP 2 LAST SEC_TYPE 0402
J 0
(-1900 4650);
DISPLAY 1.021277 (-1900 4650);
PAINT ORANGE (-1900 4650);
DISPLAY INVISIBLE (-1900 4650);
FORCEPROP 2 LAST SEC 1
J 0
(-1900 4650);
DISPLAY 0.680851 (-1900 4650);
PAINT MONO (-1900 4650);
DISPLAY INVISIBLE (-1900 4650);
FORCEPROP 2 LAST CDS_LOCATION R9A11
J 0
(-1905 4550);
DISPLAY 0.617021 (-1905 4550);
PAINT AQUA (-1905 4550);
DISPLAY INVISIBLE (-1905 4550);
FORCEPROP 1 LAST PATH I78
J 0
(-1900 4600);
DISPLAY 0.978723 (-1900 4600);
PAINT WHITE (-1900 4600);
DISPLAY INVISIBLE (-1900 4600);
FORCEPROP 2 LAST ROOM DEBUG
J 0
(-1905 4590);
DISPLAY 1.276596 (-1905 4590);
PAINT WHITE (-1905 4590);
DISPLAY INVISIBLE (-1905 4590);
FORCEADD RES..2
(-2325 4425);
FORCEPROP 1 LAST LOCATION R8A13
J 0
(-2280 4550);
DISPLAY 0.617021 (-2280 4550);
PAINT AQUA (-2280 4550);
FORCEPROP 1 LAST PART_NUMBER G21796-009
J 0
(-2285 4300);
DISPLAY 0.617021 (-2285 4300);
PAINT BLUE (-2285 4300);
FORCEPROP 1 LAST VALUE 150.0
J 0
(-2280 4500);
DISPLAY 0.617021 (-2280 4500);
PAINT SKYBLUE (-2280 4500);
FORCEPROP 1 LAST TOLERANCE 1%
J 0
(-2280 4450);
DISPLAY 0.617021 (-2280 4450);
PAINT SKYBLUE (-2280 4450);
FORCEPROP 1 LAST PACK_TYPE 0402
J 0
(-2285 4250);
DISPLAY 0.617021 (-2285 4250);
PAINT SKYBLUE (-2285 4250);
FORCEPROP 1 LAST MATERIAL CHIP
J 0
(-2285 4350);
DISPLAY 0.617021 (-2285 4350);
PAINT SKYBLUE (-2285 4350);
FORCEPROP 1 LAST WATTAGE 1/16W
J 0
(-2285 4400);
DISPLAY 0.617021 (-2285 4400);
PAINT SKYBLUE (-2285 4400);
FORCEPROP 1 LASTPIN (-2325 4325) $PN 2
J 0
(-2320 4335);
DISPLAY 0.617021 (-2320 4335);
PAINT ORANGE (-2320 4335);
FORCEPROP 1 LASTPIN (-2325 4525) $PN 1
J 0
(-2320 4487);
DISPLAY 0.617021 (-2320 4487);
PAINT ORANGE (-2320 4487);
FORCEPROP 2 LAST CDS_LIB mstr_discrete
J 0
(-2325 4425);
PAINT ORANGE (-2325 4425);
DISPLAY INVISIBLE (-2325 4425);
FORCEPROP 2 LAST SEC_TYPE 0402
J 0
(-2275 4650);
DISPLAY 1.021277 (-2275 4650);
PAINT ORANGE (-2275 4650);
DISPLAY INVISIBLE (-2275 4650);
FORCEPROP 2 LAST SEC 1
J 0
(-2275 4650);
DISPLAY 0.680851 (-2275 4650);
PAINT MONO (-2275 4650);
DISPLAY INVISIBLE (-2275 4650);
FORCEPROP 2 LAST CDS_LOCATION R8A13
J 0
(-2280 4550);
DISPLAY 0.617021 (-2280 4550);
PAINT AQUA (-2280 4550);
DISPLAY INVISIBLE (-2280 4550);
FORCEPROP 1 LAST PATH I79
J 0
(-2275 4600);
DISPLAY 0.978723 (-2275 4600);
PAINT WHITE (-2275 4600);
DISPLAY INVISIBLE (-2275 4600);
FORCEPROP 2 LAST ROOM DEBUG
J 0
(-2280 4590);
DISPLAY 1.276596 (-2280 4590);
PAINT WHITE (-2280 4590);
DISPLAY INVISIBLE (-2280 4590);
FORCEADD RES..2
(-2700 4425);
FORCEPROP 1 LAST LOCATION R8A14
J 0
(-2655 4550);
DISPLAY 0.617021 (-2655 4550);
PAINT AQUA (-2655 4550);
FORCEPROP 1 LAST PART_NUMBER G21796-009
J 0
(-2660 4300);
DISPLAY 0.617021 (-2660 4300);
PAINT BLUE (-2660 4300);
FORCEPROP 1 LAST VALUE 150.0
J 0
(-2655 4500);
DISPLAY 0.617021 (-2655 4500);
PAINT SKYBLUE (-2655 4500);
FORCEPROP 1 LAST TOLERANCE 1%
J 0
(-2655 4450);
DISPLAY 0.617021 (-2655 4450);
PAINT SKYBLUE (-2655 4450);
FORCEPROP 1 LAST PACK_TYPE 0402
J 0
(-2660 4250);
DISPLAY 0.617021 (-2660 4250);
PAINT SKYBLUE (-2660 4250);
FORCEPROP 1 LAST MATERIAL CHIP
J 0
(-2660 4350);
DISPLAY 0.617021 (-2660 4350);
PAINT SKYBLUE (-2660 4350);
FORCEPROP 1 LAST WATTAGE 1/16W
J 0
(-2660 4400);
DISPLAY 0.617021 (-2660 4400);
PAINT SKYBLUE (-2660 4400);
FORCEPROP 1 LASTPIN (-2700 4325) $PN 2
J 0
(-2695 4335);
DISPLAY 0.617021 (-2695 4335);
PAINT ORANGE (-2695 4335);
FORCEPROP 1 LASTPIN (-2700 4525) $PN 1
J 0
(-2695 4487);
DISPLAY 0.617021 (-2695 4487);
PAINT ORANGE (-2695 4487);
FORCEPROP 2 LAST CDS_LIB mstr_discrete
J 0
(-2700 4425);
PAINT ORANGE (-2700 4425);
DISPLAY INVISIBLE (-2700 4425);
FORCEPROP 2 LAST SEC_TYPE 0402
J 0
(-2650 4650);
DISPLAY 1.021277 (-2650 4650);
PAINT ORANGE (-2650 4650);
DISPLAY INVISIBLE (-2650 4650);
FORCEPROP 2 LAST SEC 1
J 0
(-2650 4650);
DISPLAY 0.680851 (-2650 4650);
PAINT MONO (-2650 4650);
DISPLAY INVISIBLE (-2650 4650);
FORCEPROP 2 LAST CDS_LOCATION R8A14
J 0
(-2655 4550);
DISPLAY 0.617021 (-2655 4550);
PAINT AQUA (-2655 4550);
DISPLAY INVISIBLE (-2655 4550);
FORCEPROP 1 LAST PATH I80
J 0
(-2650 4600);
DISPLAY 0.978723 (-2650 4600);
PAINT WHITE (-2650 4600);
DISPLAY INVISIBLE (-2650 4600);
FORCEPROP 2 LAST ROOM DEBUG
J 0
(-2655 4590);
DISPLAY 1.276596 (-2655 4590);
PAINT WHITE (-2655 4590);
DISPLAY INVISIBLE (-2655 4590);
FORCEADD OFFPAGE..1
(-300 3650);
FORCEPROP 2 LAST $XR0 112 
J 0
(-552 3650);
DISPLAY 0.638298 (-552 3650);
PAINT MONO (-552 3650);
FORCEPROP 2 LAST $XR1 21 
J 0
(-642 3650);
DISPLAY 0.638298 (-642 3650);
PAINT MONO (-642 3650);
FORCEPROP 2 LAST CDS_LIB mstr_standard
J 0
(-300 3650);
DISPLAY 2.212766 (-300 3650);
PAINT ORANGE (-300 3650);
DISPLAY INVISIBLE (-300 3650);
FORCEPROP 1 LAST OFFPAGE TRUE
J 0
(25 3525);
DISPLAY 1.404255 (25 3525);
PAINT GREEN (25 3525);
DISPLAY INVISIBLE (25 3525);
FORCEPROP 1 LAST COMMENT_BODY TRUE
J 0
(-175 3550);
DISPLAY 1.404255 (-175 3550);
PAINT PEACH (-175 3550);
DISPLAY INVISIBLE (-175 3550);
FORCEPROP 2 LAST PATH I81
J 0
(-550 3700);
DISPLAY 1.021277 (-550 3700);
PAINT ORANGE (-550 3700);
DISPLAY INVISIBLE (-550 3700);
FORCEADD OFFPAGE..1
(-300 3575);
FORCEPROP 2 LAST $XR0 21 
J 0
(-521 3575);
DISPLAY 0.638298 (-521 3575);
PAINT MONO (-521 3575);
FORCEPROP 2 LAST $XR1 112 
J 0
(-641 3575);
DISPLAY 0.638298 (-641 3575);
PAINT MONO (-641 3575);
FORCEPROP 2 LAST CDS_LIB mstr_standard
J 0
(-300 3575);
DISPLAY 2.212766 (-300 3575);
PAINT ORANGE (-300 3575);
DISPLAY INVISIBLE (-300 3575);
FORCEPROP 1 LAST OFFPAGE TRUE
J 0
(25 3450);
DISPLAY 1.404255 (25 3450);
PAINT GREEN (25 3450);
DISPLAY INVISIBLE (25 3450);
FORCEPROP 1 LAST COMMENT_BODY TRUE
J 0
(-175 3475);
DISPLAY 1.404255 (-175 3475);
PAINT PEACH (-175 3475);
DISPLAY INVISIBLE (-175 3475);
FORCEPROP 2 LAST PATH I82
J 0
(-500 3625);
DISPLAY 1.021277 (-500 3625);
PAINT ORANGE (-500 3625);
DISPLAY INVISIBLE (-500 3625);
FORCEADD OFFPAGE..1
(-300 3500);
FORCEPROP 2 LAST $XR0 21 
J 0
(-521 3500);
DISPLAY 0.638298 (-521 3500);
PAINT MONO (-521 3500);
FORCEPROP 2 LAST $XR1 55 
J 0
(-611 3500);
DISPLAY 0.638298 (-611 3500);
PAINT MONO (-611 3500);
FORCEPROP 2 LAST $XR2 112 
J 0
(-731 3500);
DISPLAY 0.638298 (-731 3500);
PAINT MONO (-731 3500);
FORCEPROP 2 LAST CDS_LIB mstr_standard
J 0
(-300 3500);
DISPLAY 2.212766 (-300 3500);
PAINT ORANGE (-300 3500);
DISPLAY INVISIBLE (-300 3500);
FORCEPROP 1 LAST OFFPAGE TRUE
J 0
(25 3375);
DISPLAY 1.404255 (25 3375);
PAINT GREEN (25 3375);
DISPLAY INVISIBLE (25 3375);
FORCEPROP 1 LAST COMMENT_BODY TRUE
J 0
(-175 3400);
DISPLAY 1.404255 (-175 3400);
PAINT PEACH (-175 3400);
DISPLAY INVISIBLE (-175 3400);
FORCEPROP 2 LAST PATH I83
J 0
(-500 3550);
DISPLAY 1.021277 (-500 3550);
PAINT ORANGE (-500 3550);
DISPLAY INVISIBLE (-500 3550);
FORCEADD OFFPAGE..1
(-300 3425);
FORCEPROP 2 LAST $XR0 21 
J 0
(-521 3425);
DISPLAY 0.638298 (-521 3425);
PAINT MONO (-521 3425);
FORCEPROP 2 LAST $XR1 55 
J 0
(-611 3425);
DISPLAY 0.638298 (-611 3425);
PAINT MONO (-611 3425);
FORCEPROP 2 LAST $XR2 112 
J 0
(-731 3425);
DISPLAY 0.638298 (-731 3425);
PAINT MONO (-731 3425);
FORCEPROP 2 LAST CDS_LIB mstr_standard
J 0
(-300 3425);
DISPLAY 2.212766 (-300 3425);
PAINT ORANGE (-300 3425);
DISPLAY INVISIBLE (-300 3425);
FORCEPROP 1 LAST OFFPAGE TRUE
J 0
(25 3300);
DISPLAY 1.404255 (25 3300);
PAINT GREEN (25 3300);
DISPLAY INVISIBLE (25 3300);
FORCEPROP 1 LAST COMMENT_BODY TRUE
J 0
(-175 3325);
DISPLAY 1.404255 (-175 3325);
PAINT PEACH (-175 3325);
DISPLAY INVISIBLE (-175 3325);
FORCEPROP 2 LAST PATH I84
J 0
(-500 3475);
DISPLAY 1.021277 (-500 3475);
PAINT ORANGE (-500 3475);
DISPLAY INVISIBLE (-500 3475);
FORCEADD RES..2
(-1950 3600);
FORCEPROP 1 LAST LOCATION R3M10
J 0
(-1905 3725);
DISPLAY 0.617021 (-1905 3725);
PAINT AQUA (-1905 3725);
FORCEPROP 1 LAST PART_NUMBER G21796-026
J 0
(-1910 3475);
DISPLAY 0.617021 (-1910 3475);
PAINT BLUE (-1910 3475);
FORCEPROP 1 LAST VALUE 1.00K
J 0
(-1905 3675);
DISPLAY 0.617021 (-1905 3675);
PAINT SKYBLUE (-1905 3675);
FORCEPROP 1 LAST TOLERANCE 1%
J 0
(-1905 3625);
DISPLAY 0.617021 (-1905 3625);
PAINT SKYBLUE (-1905 3625);
FORCEPROP 1 LAST PACK_TYPE 0402
J 0
(-1910 3425);
DISPLAY 0.617021 (-1910 3425);
PAINT SKYBLUE (-1910 3425);
FORCEPROP 1 LAST MATERIAL CHIP
J 0
(-1910 3525);
DISPLAY 0.617021 (-1910 3525);
PAINT SKYBLUE (-1910 3525);
FORCEPROP 1 LAST WATTAGE 1/16W
J 0
(-1910 3575);
DISPLAY 0.617021 (-1910 3575);
PAINT SKYBLUE (-1910 3575);
FORCEPROP 1 LASTPIN (-1950 3500) $PN 2
J 0
(-1945 3510);
DISPLAY 0.617021 (-1945 3510);
PAINT ORANGE (-1945 3510);
FORCEPROP 1 LASTPIN (-1950 3700) $PN 1
J 0
(-1945 3662);
DISPLAY 0.617021 (-1945 3662);
PAINT ORANGE (-1945 3662);
FORCEPROP 2 LAST SEC_TYPE 0402
J 0
(-1900 3825);
DISPLAY 1.021277 (-1900 3825);
PAINT ORANGE (-1900 3825);
DISPLAY INVISIBLE (-1900 3825);
FORCEPROP 2 LAST CDS_LIB mstr_discrete
J 0
(-1950 3600);
PAINT ORANGE (-1950 3600);
DISPLAY INVISIBLE (-1950 3600);
FORCEPROP 2 LAST BOM_COST DEBUG
J 0
(-1900 3775);
DISPLAY 1.617021 (-1900 3775);
PAINT WHITE (-1900 3775);
DISPLAY INVISIBLE (-1900 3775);
FORCEPROP 2 LAST SEC 1
J 0
(-1900 3825);
DISPLAY 0.680851 (-1900 3825);
PAINT MONO (-1900 3825);
DISPLAY INVISIBLE (-1900 3825);
FORCEPROP 2 LAST CDS_LOCATION R3M10
J 0
(-1905 3725);
DISPLAY 0.617021 (-1905 3725);
PAINT AQUA (-1905 3725);
DISPLAY INVISIBLE (-1905 3725);
FORCEPROP 1 LAST PATH I85
J 0
(-1900 3775);
DISPLAY 0.978723 (-1900 3775);
PAINT WHITE (-1900 3775);
DISPLAY INVISIBLE (-1900 3775);
FORCEPROP 2 LAST ROOM DEBUG
J 0
(-1900 3775);
DISPLAY 1.617021 (-1900 3775);
PAINT WHITE (-1900 3775);
DISPLAY INVISIBLE (-1900 3775);
FORCEADD OFFPAGE..5
R 2
(-1225 2775);
FORCEPROP 2 LAST $XR0 21 
J 0
(-1036 2775);
DISPLAY 0.638298 (-1036 2775);
PAINT MONO (-1036 2775);
FORCEPROP 2 LAST $XR1 112 
J 0
(-946 2775);
DISPLAY 0.638298 (-946 2775);
PAINT MONO (-946 2775);
FORCEPROP 2 LAST BOM_COST DEBUG
J 2
(-975 2875);
DISPLAY 1.617021 (-975 2875);
PAINT WHITE (-975 2875);
DISPLAY INVISIBLE (-975 2875);
FORCEPROP 2 LAST ROOM CPU_JTAG_DEBUG
J 2
(-975 2825);
DISPLAY 1.617021 (-975 2825);
PAINT WHITE (-975 2825);
DISPLAY INVISIBLE (-975 2825);
FORCEPROP 2 LAST CDS_LIB mstr_standard
J 0
(-1225 2775);
PAINT ORANGE (-1225 2775);
DISPLAY INVISIBLE (-1225 2775);
FORCEPROP 1 LAST OFFPAGE TRUE
J 2
(-1550 2650);
DISPLAY 1.404255 (-1550 2650);
PAINT GREEN (-1550 2650);
DISPLAY INVISIBLE (-1550 2650);
FORCEPROP 1 LAST COMMENT_BODY TRUE
J 2
(-1325 2700);
DISPLAY 1.404255 (-1325 2700);
PAINT PEACH (-1325 2700);
DISPLAY INVISIBLE (-1325 2700);
FORCEPROP 2 LAST PATH I86
J 0
(-975 2825);
DISPLAY 1.021277 (-975 2825);
PAINT ORANGE (-975 2825);
DISPLAY INVISIBLE (-975 2825);
FORCEADD OFFPAGE..1
R 2
(-1225 2575);
FORCEPROP 2 LAST $XR0 112 
J 0
(-1039 2575);
DISPLAY 0.638298 (-1039 2575);
PAINT MONO (-1039 2575);
FORCEPROP 2 LAST BOM_COST DEBUG
J 2
(-975 2675);
DISPLAY 1.617021 (-975 2675);
PAINT WHITE (-975 2675);
DISPLAY INVISIBLE (-975 2675);
FORCEPROP 2 LAST ROOM CPU_JTAG_DEBUG
J 2
(-975 2625);
DISPLAY 1.617021 (-975 2625);
PAINT WHITE (-975 2625);
DISPLAY INVISIBLE (-975 2625);
FORCEPROP 2 LAST CDS_LIB mstr_standard
J 0
(-1225 2575);
PAINT ORANGE (-1225 2575);
DISPLAY INVISIBLE (-1225 2575);
FORCEPROP 1 LAST OFFPAGE TRUE
J 2
(-1550 2450);
DISPLAY 1.404255 (-1550 2450);
PAINT GREEN (-1550 2450);
DISPLAY INVISIBLE (-1550 2450);
FORCEPROP 1 LAST COMMENT_BODY TRUE
J 2
(-1350 2475);
DISPLAY 1.404255 (-1350 2475);
PAINT PEACH (-1350 2475);
DISPLAY INVISIBLE (-1350 2475);
FORCEPROP 2 LAST PATH I87
J 0
(-925 2625);
DISPLAY 1.021277 (-925 2625);
PAINT ORANGE (-925 2625);
DISPLAY INVISIBLE (-925 2625);
FORCEADD OFFPAGE..5
R 2
(-1225 2375);
FORCEPROP 2 LAST $XR0 21 
J 0
(-1036 2375);
DISPLAY 0.638298 (-1036 2375);
PAINT MONO (-1036 2375);
FORCEPROP 2 LAST $XR1 55 
J 0
(-946 2375);
DISPLAY 0.638298 (-946 2375);
PAINT MONO (-946 2375);
FORCEPROP 2 LAST $XR2 112 
J 0
(-856 2375);
DISPLAY 0.638298 (-856 2375);
PAINT MONO (-856 2375);
FORCEPROP 2 LAST BOM_COST DEBUG
J 2
(-975 2475);
DISPLAY 1.617021 (-975 2475);
PAINT WHITE (-975 2475);
DISPLAY INVISIBLE (-975 2475);
FORCEPROP 2 LAST ROOM CPU_JTAG_DEBUG
J 2
(-975 2425);
DISPLAY 1.617021 (-975 2425);
PAINT WHITE (-975 2425);
DISPLAY INVISIBLE (-975 2425);
FORCEPROP 2 LAST CDS_LIB mstr_standard
J 0
(-1225 2375);
PAINT ORANGE (-1225 2375);
DISPLAY INVISIBLE (-1225 2375);
FORCEPROP 1 LAST OFFPAGE TRUE
J 2
(-1550 2250);
DISPLAY 1.404255 (-1550 2250);
PAINT GREEN (-1550 2250);
DISPLAY INVISIBLE (-1550 2250);
FORCEPROP 1 LAST COMMENT_BODY TRUE
J 2
(-1325 2300);
DISPLAY 1.404255 (-1325 2300);
PAINT PEACH (-1325 2300);
DISPLAY INVISIBLE (-1325 2300);
FORCEPROP 2 LAST PATH I88
J 0
(-875 2425);
DISPLAY 1.021277 (-875 2425);
PAINT ORANGE (-875 2425);
DISPLAY INVISIBLE (-875 2425);
FORCEADD OFFPAGE..5
R 2
(-1225 2175);
FORCEPROP 2 LAST $XR0 21 
J 0
(-1036 2175);
DISPLAY 0.638298 (-1036 2175);
PAINT MONO (-1036 2175);
FORCEPROP 2 LAST $XR1 55 
J 0
(-946 2175);
DISPLAY 0.638298 (-946 2175);
PAINT MONO (-946 2175);
FORCEPROP 2 LAST $XR2 112 
J 0
(-856 2175);
DISPLAY 0.638298 (-856 2175);
PAINT MONO (-856 2175);
FORCEPROP 2 LAST BOM_COST DEBUG
J 2
(-975 2275);
DISPLAY 1.617021 (-975 2275);
PAINT WHITE (-975 2275);
DISPLAY INVISIBLE (-975 2275);
FORCEPROP 2 LAST ROOM CPU_JTAG_DEBUG
J 2
(-975 2225);
DISPLAY 1.617021 (-975 2225);
PAINT WHITE (-975 2225);
DISPLAY INVISIBLE (-975 2225);
FORCEPROP 2 LAST CDS_LIB mstr_standard
J 0
(-1225 2175);
PAINT ORANGE (-1225 2175);
DISPLAY INVISIBLE (-1225 2175);
FORCEPROP 1 LAST OFFPAGE TRUE
J 2
(-1550 2050);
DISPLAY 1.404255 (-1550 2050);
PAINT GREEN (-1550 2050);
DISPLAY INVISIBLE (-1550 2050);
FORCEPROP 1 LAST COMMENT_BODY TRUE
J 2
(-1325 2100);
DISPLAY 1.404255 (-1325 2100);
PAINT PEACH (-1325 2100);
DISPLAY INVISIBLE (-1325 2100);
FORCEPROP 2 LAST PATH I89
J 0
(-875 2225);
DISPLAY 1.021277 (-875 2225);
PAINT ORANGE (-875 2225);
DISPLAY INVISIBLE (-875 2225);
FORCEADD OFFPAGE..5
R 2
(-1225 1550);
FORCEPROP 2 LAST $XR0 21 
J 0
(-1036 1550);
DISPLAY 0.638298 (-1036 1550);
PAINT MONO (-1036 1550);
FORCEPROP 2 LAST $XR1 55 
J 0
(-946 1550);
DISPLAY 0.638298 (-946 1550);
PAINT MONO (-946 1550);
FORCEPROP 2 LAST $XR2 112 
J 0
(-856 1550);
DISPLAY 0.638298 (-856 1550);
PAINT MONO (-856 1550);
FORCEPROP 2 LAST BOM_COST DEBUG
J 2
(-975 1650);
DISPLAY 1.617021 (-975 1650);
PAINT WHITE (-975 1650);
DISPLAY INVISIBLE (-975 1650);
FORCEPROP 2 LAST ROOM CPU_JTAG_DEBUG
J 2
(-975 1600);
DISPLAY 1.617021 (-975 1600);
PAINT WHITE (-975 1600);
DISPLAY INVISIBLE (-975 1600);
FORCEPROP 2 LAST CDS_LIB mstr_standard
J 0
(-1225 1550);
PAINT ORANGE (-1225 1550);
DISPLAY INVISIBLE (-1225 1550);
FORCEPROP 1 LAST OFFPAGE TRUE
J 2
(-1550 1425);
DISPLAY 1.404255 (-1550 1425);
PAINT GREEN (-1550 1425);
DISPLAY INVISIBLE (-1550 1425);
FORCEPROP 1 LAST COMMENT_BODY TRUE
J 2
(-1325 1475);
DISPLAY 1.404255 (-1325 1475);
PAINT PEACH (-1325 1475);
DISPLAY INVISIBLE (-1325 1475);
FORCEPROP 2 LAST PATH I90
J 0
(-875 1600);
DISPLAY 1.021277 (-875 1600);
PAINT ORANGE (-875 1600);
DISPLAY INVISIBLE (-875 1600);
FORCEADD OFFPAGE..1
R 2
(-1225 1350);
FORCEPROP 2 LAST $XR0 21 
J 0
(-1039 1350);
DISPLAY 0.638298 (-1039 1350);
PAINT MONO (-1039 1350);
FORCEPROP 2 LAST $XR1 55 
J 0
(-949 1350);
DISPLAY 0.638298 (-949 1350);
PAINT MONO (-949 1350);
FORCEPROP 2 LAST $XR2 112 
J 0
(-859 1350);
DISPLAY 0.638298 (-859 1350);
PAINT MONO (-859 1350);
FORCEPROP 2 LAST BOM_COST DEBUG
J 2
(-975 1450);
DISPLAY 1.617021 (-975 1450);
PAINT WHITE (-975 1450);
DISPLAY INVISIBLE (-975 1450);
FORCEPROP 2 LAST ROOM CPU_JTAG_DEBUG
J 2
(-975 1400);
DISPLAY 1.617021 (-975 1400);
PAINT WHITE (-975 1400);
DISPLAY INVISIBLE (-975 1400);
FORCEPROP 2 LAST CDS_LIB mstr_standard
J 0
(-1225 1350);
PAINT ORANGE (-1225 1350);
DISPLAY INVISIBLE (-1225 1350);
FORCEPROP 1 LAST OFFPAGE TRUE
J 2
(-1550 1225);
DISPLAY 1.404255 (-1550 1225);
PAINT GREEN (-1550 1225);
DISPLAY INVISIBLE (-1550 1225);
FORCEPROP 1 LAST COMMENT_BODY TRUE
J 2
(-1350 1250);
DISPLAY 1.404255 (-1350 1250);
PAINT PEACH (-1350 1250);
DISPLAY INVISIBLE (-1350 1250);
FORCEPROP 2 LAST PATH I91
J 0
(-875 1400);
DISPLAY 1.021277 (-875 1400);
PAINT ORANGE (-875 1400);
DISPLAY INVISIBLE (-875 1400);
FORCEADD OFFPAGE..5
R 2
(-1225 1150);
FORCEPROP 2 LAST $XR0 21 
J 0
(-1036 1150);
DISPLAY 0.638298 (-1036 1150);
PAINT MONO (-1036 1150);
FORCEPROP 2 LAST $XR1 55 
J 0
(-946 1150);
DISPLAY 0.638298 (-946 1150);
PAINT MONO (-946 1150);
FORCEPROP 2 LAST $XR2 112 
J 0
(-856 1150);
DISPLAY 0.638298 (-856 1150);
PAINT MONO (-856 1150);
FORCEPROP 2 LAST BOM_COST DEBUG
J 2
(-975 1250);
DISPLAY 1.617021 (-975 1250);
PAINT WHITE (-975 1250);
DISPLAY INVISIBLE (-975 1250);
FORCEPROP 2 LAST ROOM CPU_JTAG_DEBUG
J 2
(-975 1200);
DISPLAY 1.617021 (-975 1200);
PAINT WHITE (-975 1200);
DISPLAY INVISIBLE (-975 1200);
FORCEPROP 2 LAST CDS_LIB mstr_standard
J 0
(-1225 1150);
PAINT ORANGE (-1225 1150);
DISPLAY INVISIBLE (-1225 1150);
FORCEPROP 1 LAST OFFPAGE TRUE
J 2
(-1550 1025);
DISPLAY 1.404255 (-1550 1025);
PAINT GREEN (-1550 1025);
DISPLAY INVISIBLE (-1550 1025);
FORCEPROP 1 LAST COMMENT_BODY TRUE
J 2
(-1325 1075);
DISPLAY 1.404255 (-1325 1075);
PAINT PEACH (-1325 1075);
DISPLAY INVISIBLE (-1325 1075);
FORCEPROP 2 LAST PATH I92
J 0
(-875 1200);
DISPLAY 1.021277 (-875 1200);
PAINT ORANGE (-875 1200);
DISPLAY INVISIBLE (-875 1200);
FORCEADD OFFPAGE..5
R 2
(-1225 950);
FORCEPROP 2 LAST $XR0 21 
J 0
(-1036 950);
DISPLAY 0.638298 (-1036 950);
PAINT MONO (-1036 950);
FORCEPROP 2 LAST $XR1 55 
J 0
(-946 950);
DISPLAY 0.638298 (-946 950);
PAINT MONO (-946 950);
FORCEPROP 2 LAST $XR2 112 
J 0
(-856 950);
DISPLAY 0.638298 (-856 950);
PAINT MONO (-856 950);
FORCEPROP 2 LAST BOM_COST DEBUG
J 2
(-975 1050);
DISPLAY 1.617021 (-975 1050);
PAINT WHITE (-975 1050);
DISPLAY INVISIBLE (-975 1050);
FORCEPROP 2 LAST ROOM CPU_JTAG_DEBUG
J 2
(-975 1000);
DISPLAY 1.617021 (-975 1000);
PAINT WHITE (-975 1000);
DISPLAY INVISIBLE (-975 1000);
FORCEPROP 2 LAST CDS_LIB mstr_standard
J 0
(-1225 950);
PAINT ORANGE (-1225 950);
DISPLAY INVISIBLE (-1225 950);
FORCEPROP 1 LAST OFFPAGE TRUE
J 2
(-1550 825);
DISPLAY 1.404255 (-1550 825);
PAINT GREEN (-1550 825);
DISPLAY INVISIBLE (-1550 825);
FORCEPROP 1 LAST COMMENT_BODY TRUE
J 2
(-1325 875);
DISPLAY 1.404255 (-1325 875);
PAINT PEACH (-1325 875);
DISPLAY INVISIBLE (-1325 875);
FORCEPROP 2 LAST PATH I93
J 0
(-875 1000);
DISPLAY 1.021277 (-875 1000);
PAINT ORANGE (-875 1000);
DISPLAY INVISIBLE (-875 1000);
FORCEADD RES..2
(-2325 3600);
FORCEPROP 1 LAST LOCATION R8B2
J 0
(-2280 3725);
DISPLAY 0.617021 (-2280 3725);
PAINT AQUA (-2280 3725);
FORCEPROP 1 LAST PART_NUMBER G21796-026
J 0
(-2285 3475);
DISPLAY 0.617021 (-2285 3475);
PAINT BLUE (-2285 3475);
FORCEPROP 1 LAST VALUE 1.00K
J 0
(-2280 3675);
DISPLAY 0.617021 (-2280 3675);
PAINT SKYBLUE (-2280 3675);
FORCEPROP 1 LAST TOLERANCE 1%
J 0
(-2280 3625);
DISPLAY 0.617021 (-2280 3625);
PAINT SKYBLUE (-2280 3625);
FORCEPROP 1 LAST PACK_TYPE 0402
J 0
(-2285 3425);
DISPLAY 0.617021 (-2285 3425);
PAINT SKYBLUE (-2285 3425);
FORCEPROP 1 LAST MATERIAL CHIP
J 0
(-2285 3525);
DISPLAY 0.617021 (-2285 3525);
PAINT SKYBLUE (-2285 3525);
FORCEPROP 1 LAST WATTAGE 1/16W
J 0
(-2285 3575);
DISPLAY 0.617021 (-2285 3575);
PAINT SKYBLUE (-2285 3575);
FORCEPROP 1 LASTPIN (-2325 3500) $PN 2
J 0
(-2320 3510);
DISPLAY 0.617021 (-2320 3510);
PAINT ORANGE (-2320 3510);
FORCEPROP 1 LASTPIN (-2325 3700) $PN 1
J 0
(-2320 3662);
DISPLAY 0.617021 (-2320 3662);
PAINT ORANGE (-2320 3662);
FORCEPROP 2 LAST SEC_TYPE 0402
J 0
(-2275 3825);
DISPLAY 1.021277 (-2275 3825);
PAINT ORANGE (-2275 3825);
DISPLAY INVISIBLE (-2275 3825);
FORCEPROP 2 LAST CDS_LIB mstr_discrete
J 0
(-2325 3600);
PAINT ORANGE (-2325 3600);
DISPLAY INVISIBLE (-2325 3600);
FORCEPROP 2 LAST BOM_COST DEBUG
J 0
(-2275 3775);
DISPLAY 1.617021 (-2275 3775);
PAINT WHITE (-2275 3775);
DISPLAY INVISIBLE (-2275 3775);
FORCEPROP 2 LAST SEC 1
J 0
(-2275 3825);
DISPLAY 0.680851 (-2275 3825);
PAINT MONO (-2275 3825);
DISPLAY INVISIBLE (-2275 3825);
FORCEPROP 2 LAST CDS_LOCATION R8B2
J 0
(-2280 3725);
DISPLAY 0.617021 (-2280 3725);
PAINT AQUA (-2280 3725);
DISPLAY INVISIBLE (-2280 3725);
FORCEPROP 1 LAST PATH I94
J 0
(-2275 3775);
DISPLAY 0.978723 (-2275 3775);
PAINT WHITE (-2275 3775);
DISPLAY INVISIBLE (-2275 3775);
FORCEPROP 2 LAST ROOM DEBUG
J 0
(-2275 3775);
DISPLAY 1.617021 (-2275 3775);
PAINT WHITE (-2275 3775);
DISPLAY INVISIBLE (-2275 3775);
FORCEADD RES..2
(-2700 3600);
FORCEPROP 1 LAST LOCATION R8B1
J 0
(-2655 3725);
DISPLAY 0.617021 (-2655 3725);
PAINT AQUA (-2655 3725);
FORCEPROP 1 LAST PART_NUMBER G21796-208
J 0
(-2660 3475);
DISPLAY 0.617021 (-2660 3475);
PAINT BLUE (-2660 3475);
FORCEPROP 1 LAST VALUE 51.1
J 0
(-2655 3675);
DISPLAY 0.617021 (-2655 3675);
PAINT SKYBLUE (-2655 3675);
FORCEPROP 1 LAST TOLERANCE 1.0%
J 0
(-2655 3625);
DISPLAY 0.617021 (-2655 3625);
PAINT SKYBLUE (-2655 3625);
FORCEPROP 1 LAST PACK_TYPE 0402
J 0
(-2660 3425);
DISPLAY 0.617021 (-2660 3425);
PAINT SKYBLUE (-2660 3425);
FORCEPROP 1 LAST MATERIAL CHIP
J 0
(-2660 3525);
DISPLAY 0.617021 (-2660 3525);
PAINT SKYBLUE (-2660 3525);
FORCEPROP 1 LAST WATTAGE 1/16W
J 0
(-2660 3575);
DISPLAY 0.617021 (-2660 3575);
PAINT SKYBLUE (-2660 3575);
FORCEPROP 1 LASTPIN (-2700 3500) $PN 2
J 0
(-2695 3510);
DISPLAY 0.617021 (-2695 3510);
PAINT WHITE (-2695 3510);
FORCEPROP 1 LASTPIN (-2700 3700) $PN 1
J 0
(-2695 3662);
DISPLAY 0.617021 (-2695 3662);
PAINT WHITE (-2695 3662);
FORCEPROP 2 LAST BOM_COST DEBUG
J 0
(-2650 3775);
DISPLAY 1.617021 (-2650 3775);
PAINT WHITE (-2650 3775);
DISPLAY INVISIBLE (-2650 3775);
FORCEPROP 2 LAST CDS_LIB mstr_discrete
J 0
(-2700 3600);
DISPLAY 2.212766 (-2700 3600);
PAINT ORANGE (-2700 3600);
DISPLAY INVISIBLE (-2700 3600);
FORCEPROP 2 LAST CDS_SEC 1
J 0
(-2650 3825);
PAINT MONO (-2650 3825);
DISPLAY INVISIBLE (-2650 3825);
FORCEPROP 2 LAST $SEC 1
J 0
(-2650 3825);
PAINT MONO (-2650 3825);
DISPLAY INVISIBLE (-2650 3825);
FORCEPROP 2 LAST CDS_LOCATION R8B1
J 0
(-2655 3725);
DISPLAY 0.617021 (-2655 3725);
PAINT AQUA (-2655 3725);
DISPLAY INVISIBLE (-2655 3725);
FORCEPROP 1 LAST PATH I95
J 0
(-2650 3775);
DISPLAY 0.978723 (-2650 3775);
PAINT WHITE (-2650 3775);
DISPLAY INVISIBLE (-2650 3775);
FORCEPROP 2 LAST ROOM DEBUG
J 0
(-2650 3775);
DISPLAY 1.617021 (-2650 3775);
PAINT WHITE (-2650 3775);
DISPLAY INVISIBLE (-2650 3775);
FORCEADD GND..1
(-2700 3300);
FORCEPROP 3 LASTPIN (-2700 3350) SIG_NAME GND\g
J 0
(-2690 3360);
DISPLAY 0.659574 (-2690 3360);
PAINT MONO (-2690 3360);
DISPLAY INVISIBLE (-2690 3360);
FORCEPROP 1 LAST VOLTAGE 0.0V
J 0
(-2745 3257);
DISPLAY 0.340426 (-2745 3257);
PAINT SKYBLUE (-2745 3257);
DISPLAY INVISIBLE (-2745 3257);
FORCEPROP 1 LAST SIZE 1B
J 0
(-2625 3250);
DISPLAY 2.382979 (-2625 3250);
PAINT GREEN (-2625 3250);
DISPLAY INVISIBLE (-2625 3250);
FORCEPROP 2 LAST CDS_LIB mstr_symbols
J 0
(-2700 3300);
DISPLAY 2.212766 (-2700 3300);
PAINT ORANGE (-2700 3300);
DISPLAY INVISIBLE (-2700 3300);
FORCEPROP 1 LAST BODY_TYPE PLUMBING
J 0
(-2745 3257);
DISPLAY 0.340426 (-2745 3257);
PAINT GREEN (-2745 3257);
DISPLAY INVISIBLE (-2745 3257);
FORCEPROP 1 LAST PATH I96
J 0
(-2625 3300);
DISPLAY 0.872340 (-2625 3300);
PAINT AQUA (-2625 3300);
DISPLAY INVISIBLE (-2625 3300);
FORCEPROP 1 LAST HDL_POWER GND
J 0
(-2700 3450);
PAINT GREEN (-2700 3450);
DISPLAY INVISIBLE (-2700 3450);
FORCEADD OFFPAGE..1
(-3200 4250);
FORCEPROP 2 LAST $XR0 111 
J 0
(-3482 4250);
DISPLAY 0.638298 (-3482 4250);
PAINT MONO (-3482 4250);
FORCEPROP 2 LAST $XR1 118 
J 0
(-3602 4250);
DISPLAY 0.638298 (-3602 4250);
PAINT MONO (-3602 4250);
FORCEPROP 2 LAST $XR2 112 
J 0
(-3722 4250);
DISPLAY 0.638298 (-3722 4250);
PAINT MONO (-3722 4250);
FORCEPROP 2 LAST CDS_LIB mstr_standard
J 0
(-3200 4250);
DISPLAY 2.212766 (-3200 4250);
PAINT ORANGE (-3200 4250);
DISPLAY INVISIBLE (-3200 4250);
FORCEPROP 1 LAST OFFPAGE TRUE
J 0
(-2875 4125);
DISPLAY 1.404255 (-2875 4125);
PAINT GREEN (-2875 4125);
DISPLAY INVISIBLE (-2875 4125);
FORCEPROP 1 LAST COMMENT_BODY TRUE
J 0
(-3075 4150);
DISPLAY 1.404255 (-3075 4150);
PAINT PEACH (-3075 4150);
DISPLAY INVISIBLE (-3075 4150);
FORCEPROP 2 LAST PATH I97
J 0
(-3450 4300);
DISPLAY 1.021277 (-3450 4300);
PAINT ORANGE (-3450 4300);
DISPLAY INVISIBLE (-3450 4300);
FORCEADD OFFPAGE..1
(-3200 4175);
FORCEPROP 2 LAST $XR0 111 
J 0
(-3482 4175);
DISPLAY 0.638298 (-3482 4175);
PAINT MONO (-3482 4175);
FORCEPROP 2 LAST $XR1 118 
J 0
(-3602 4175);
DISPLAY 0.638298 (-3602 4175);
PAINT MONO (-3602 4175);
FORCEPROP 2 LAST $XR2 112 
J 0
(-3722 4175);
DISPLAY 0.638298 (-3722 4175);
PAINT MONO (-3722 4175);
FORCEPROP 2 LAST CDS_LIB mstr_standard
J 0
(-3200 4175);
DISPLAY 2.212766 (-3200 4175);
PAINT ORANGE (-3200 4175);
DISPLAY INVISIBLE (-3200 4175);
FORCEPROP 1 LAST OFFPAGE TRUE
J 0
(-2875 4050);
DISPLAY 1.404255 (-2875 4050);
PAINT GREEN (-2875 4050);
DISPLAY INVISIBLE (-2875 4050);
FORCEPROP 1 LAST COMMENT_BODY TRUE
J 0
(-3075 4075);
DISPLAY 1.404255 (-3075 4075);
PAINT PEACH (-3075 4075);
DISPLAY INVISIBLE (-3075 4075);
FORCEPROP 2 LAST PATH I98
J 0
(-3450 4225);
DISPLAY 1.021277 (-3450 4225);
PAINT ORANGE (-3450 4225);
DISPLAY INVISIBLE (-3450 4225);
FORCEADD OFFPAGE..1
(-3200 4100);
FORCEPROP 2 LAST $XR0 112 
J 0
(-3482 4100);
DISPLAY 0.638298 (-3482 4100);
PAINT MONO (-3482 4100);
FORCEPROP 2 LAST $XR1 118 
J 0
(-3602 4100);
DISPLAY 0.638298 (-3602 4100);
PAINT MONO (-3602 4100);
FORCEPROP 2 LAST $XR2 111 
J 0
(-3722 4100);
DISPLAY 0.638298 (-3722 4100);
PAINT MONO (-3722 4100);
FORCEPROP 2 LAST CDS_LIB mstr_standard
J 0
(-3200 4100);
DISPLAY 2.212766 (-3200 4100);
PAINT ORANGE (-3200 4100);
DISPLAY INVISIBLE (-3200 4100);
FORCEPROP 1 LAST OFFPAGE TRUE
J 0
(-2875 3975);
DISPLAY 1.404255 (-2875 3975);
PAINT GREEN (-2875 3975);
DISPLAY INVISIBLE (-2875 3975);
FORCEPROP 1 LAST COMMENT_BODY TRUE
J 0
(-3075 4000);
DISPLAY 1.404255 (-3075 4000);
PAINT PEACH (-3075 4000);
DISPLAY INVISIBLE (-3075 4000);
FORCEPROP 2 LAST PATH I99
J 0
(-3450 4150);
DISPLAY 1.021277 (-3450 4150);
PAINT ORANGE (-3450 4150);
DISPLAY INVISIBLE (-3450 4150);
FORCEADD CAD_NOTE..1
(2375 2950);
FORCEPROP 0 LAST L1 PLACE PULL-UP RESISTORS WITHIN 1.5'' OF CPU1
J 0
(2250 2825);
DISPLAY 0.744681 (2250 2825);
PAINT WHITE (2250 2825);
FORCEPROP 2 LAST CDS_LIB mstr_symbols
J 0
(2375 2950);
PAINT ORANGE (2375 2950);
DISPLAY INVISIBLE (2375 2950);
FORCEPROP 1 LAST COMMENT_BODY TRUE
J 0
(2400 3050);
DISPLAY 2.212766 (2400 3050);
PAINT PEACH (2400 3050);
DISPLAY INVISIBLE (2400 3050);
FORCEADD CAD_NOTE..1
(-1825 600);
FORCEPROP 0 LAST L1 PLACE CAP NEXT TO FET SWITCH
J 0
(-1975 475);
DISPLAY 0.595745 (-1975 475);
PAINT WHITE (-1975 475);
FORCEPROP 2 LAST CDS_LIB mstr_symbols
J 0
(-1825 600);
PAINT MONO (-1825 600);
DISPLAY INVISIBLE (-1825 600);
FORCEPROP 1 LAST COMMENT_BODY TRUE
J 0
(-1800 700);
DISPLAY 2.212766 (-1800 700);
PAINT PEACH (-1800 700);
DISPLAY INVISIBLE (-1800 700);
FORCEADD CAD_NOTE..1
(-550 4450);
FORCEPROP 0 LAST L1 PLACE PULL-UP RESISTORS WITHIN 1.5'' OF CPU0
J 0
(-675 4325);
DISPLAY 0.744681 (-675 4325);
PAINT WHITE (-675 4325);
FORCEPROP 2 LAST CDS_LIB mstr_symbols
J 0
(-550 4450);
PAINT MONO (-550 4450);
DISPLAY INVISIBLE (-550 4450);
FORCEPROP 1 LAST COMMENT_BODY TRUE
J 0
(-525 4550);
DISPLAY 2.212766 (-525 4550);
PAINT PEACH (-525 4550);
DISPLAY INVISIBLE (-525 4550);
FORCEADD CAD_NOTE..1
(3825 3850);
FORCEPROP 2 LAST CDS_LIB mstr_symbols
J 0
(3825 3850);
PAINT MONO (3825 3850);
DISPLAY INVISIBLE (3825 3850);
FORCEPROP 1 LAST COMMENT_BODY TRUE
J 0
(3850 3950);
DISPLAY 2.212766 (3850 3950);
PAINT PEACH (3850 3950);
DISPLAY INVISIBLE (3850 3950);
FORCEADD CAD_NOTE..1
(-1675 1975);
FORCEPROP 0 LAST L1 PLACE CAP NEXT TO FET SWITCH
J 0
(-1825 1850);
DISPLAY 0.595745 (-1825 1850);
PAINT WHITE (-1825 1850);
FORCEPROP 2 LAST CDS_LIB mstr_symbols
J 0
(-1675 1975);
PAINT MONO (-1675 1975);
DISPLAY INVISIBLE (-1675 1975);
FORCEPROP 1 LAST COMMENT_BODY TRUE
J 0
(-1650 2075);
DISPLAY 2.212766 (-1650 2075);
PAINT PEACH (-1650 2075);
DISPLAY INVISIBLE (-1650 2075);
FORCEADD CAD_NOTE..1
(-3525 4800);
FORCEPROP 0 LAST L1 PLACE PULL-UP RESISTORS WITHIN 1.5'' OF PCH
J 0
(-3650 4675);
DISPLAY 0.744681 (-3650 4675);
PAINT WHITE (-3650 4675);
FORCEPROP 2 LAST CDS_LIB mstr_symbols
J 0
(-3525 4800);
PAINT MONO (-3525 4800);
DISPLAY INVISIBLE (-3525 4800);
FORCEPROP 1 LAST COMMENT_BODY TRUE
J 0
(-3500 4900);
DISPLAY 2.212766 (-3500 4900);
PAINT PEACH (-3500 4900);
DISPLAY INVISIBLE (-3500 4900);
FORCEADD CAD_NOTE..1
(1250 1200);
FORCEPROP 0 LAST L1 PLACE PD RESISTORS WITHIN 1.1'' OF CPU PACKAGE
J 0
(1125 1075);
DISPLAY 0.744681 (1125 1075);
PAINT WHITE (1125 1075);
FORCEPROP 2 LAST CDS_LIB mstr_symbols
J 0
(1250 1200);
PAINT ORANGE (1250 1200);
DISPLAY INVISIBLE (1250 1200);
FORCEPROP 1 LAST COMMENT_BODY TRUE
J 0
(1275 1300);
DISPLAY 2.212766 (1275 1300);
PAINT PEACH (1275 1300);
DISPLAY INVISIBLE (1275 1300);
FORCEADD CAD_NOTE..1
(-3475 3325);
FORCEPROP 0 LAST L1 PLACE PULL-DOWN RESISTORS WITHIN 1.1'' OF PCH
J 0
(-3625 3200);
DISPLAY 0.744681 (-3625 3200);
PAINT WHITE (-3625 3200);
FORCEPROP 2 LAST CDS_LIB mstr_symbols
J 0
(-3475 3325);
PAINT MONO (-3475 3325);
DISPLAY INVISIBLE (-3475 3325);
FORCEPROP 1 LAST COMMENT_BODY TRUE
J 0
(-3450 3425);
DISPLAY 2.212766 (-3450 3425);
PAINT PEACH (-3450 3425);
DISPLAY INVISIBLE (-3450 3425);
FORCEADD INTEL_CORP_BPAGE..1
(4250 200);
FORCEPROP 1 LAST CDS_CON_LAST_MODIFIED Tue Dec 01 11:51:54 2015
J 0
(2825 525);
PAINT ORANGE (2825 525);
DISPLAY INVISIBLE (2825 525);
FORCEPROP 1 LAST CUSTOM_TXT_CDS <CURRENT_DESIGN_SHEET> OF <TOTAL_DESIGN_SHEETS>
J 0
(3750 225);
PAINT GREEN (3750 225);
FORCEPROP 1 LAST CUSTOM_TXT_CDS <CON_LAST_MODIFIED>
J 0
(2325 550);
PAINT GREEN (2325 550);
FORCEPROP 2 LAST CUSTOM_TXT_CDS <XR_PAGE_TITLE>
J 0
(-3640 5450);
DISPLAY 0.638298 (-3640 5450);
PAINT PINK (-3640 5450);
DISPLAY INVISIBLE (-3640 5450);
FORCEPROP 1 LAST SCH_ADDRESS3 Santa Clara, CA 95052-8119
J 0
(275 225);
DISPLAY 0.617021 (275 225);
PAINT YELLOW (275 225);
FORCEPROP 1 LAST SCH_ADDRESS2 P.O. BOX 58119
J 0
(275 275);
DISPLAY 0.617021 (275 275);
PAINT YELLOW (275 275);
FORCEPROP 1 LAST SCH_ADDRESS1 2200 Mission College Blvd.
J 0
(275 325);
DISPLAY 0.617021 (275 325);
PAINT YELLOW (275 325);
FORCEPROP 1 LAST SCH_TITLE CPU & PCH XDP (2-2)
J 0
(-3700 250);
DISPLAY 1.212766 (-3700 250);
PAINT YELLOW (-3700 250);
FORCEPROP 1 LAST SCH_NUMBER H4694802
J 0
(2950 350);
DISPLAY 1.212766 (2950 350);
PAINT YELLOW (2950 350);
FORCEPROP 1 LAST SCH_DEPT BESD
J 1
(-200 300);
DISPLAY 1.212766 (-200 300);
PAINT YELLOW (-200 300);
FORCEPROP 1 LAST SCH_REV 2.420
J 0
(4000 350);
DISPLAY 0.978723 (4000 350);
PAINT YELLOW (4000 350);
FORCEPROP 2 LAST PAGE_BORDER TRUE
J 0
(-3640 5450);
DISPLAY 0.638298 (-3640 5450);
PAINT PINK (-3640 5450);
DISPLAY INVISIBLE (-3640 5450);
FORCEPROP 2 LAST CDS_LIB mstr_symbols
J 0
(4250 200);
PAINT MONO (4250 200);
DISPLAY INVISIBLE (4250 200);
FORCEPROP 1 LAST COMMENT_BODY TRUE
J 0
(4262 212);
DISPLAY 0.468085 (4262 212);
PAINT PEACH (4262 212);
DISPLAY INVISIBLE (4262 212);
FORCEPROP 2 LAST CDS_XR_PAGE_TITLE CR-112 : @BASEBOARD_FAB2_LIB.BASEBOARD_FAB2(SCH_1):PAGE112
J 0
(-3640 5450);
DISPLAY 0.638298 (-3640 5450);
PAINT PINK (-3640 5450);
DISPLAY INVISIBLE (-3640 5450);
WIRE 16 -1 (3175 2500)(3175 2600);
WIRE 16 -1 (3175 2600)(3500 2600);
WIRE 16 -1 (3500 2650)(3500 2600);
WIRE 16 -1 (3500 2600)(3500 2500);
WIRE 16 -1 (1600 2500)(1600 2625);
WIRE 16 -1 (1950 2625)(1600 2625);
WIRE 16 -1 (1950 2675)(1950 2625);
WIRE 16 -1 (1950 2625)(1950 2500);
WIRE 16 -1 (-2700 4525)(-2700 4650);
WIRE 16 -1 (-2325 4650)(-2700 4650);
WIRE 16 -1 (-2325 4525)(-2325 4650);
WIRE 16 -1 (-1950 4650)(-2325 4650);
WIRE 16 -1 (-1575 4650)(-1950 4650);
WIRE 16 -1 (-1950 4650)(-1950 4525);
WIRE 16 -1 (-1575 4525)(-1575 4650);
WIRE 16 -1 (-1200 4650)(-1575 4650);
WIRE 16 -1 (-1200 4700)(-1200 4650);
WIRE 16 -1 (-1200 4650)(-1200 4525);
WIRE 16 -1 (3550 3625)(3550 3575);
WIRE 16 -1 (500 2500)(500 2625);
WIRE 16 -1 (875 2500)(875 2575);
WIRE 16 -1 (1225 2575)(875 2575);
WIRE 16 -1 (1225 2625)(1225 2575);
WIRE 16 -1 (1225 2575)(1225 2500);
WIRE 16 -1 (-1125 1750)(-1125 1725);
WIRE 16 -1 (-1350 525)(-1350 500);
WIRE 16 -1 (3550 3875)(3550 3825);
WIRE 16 -1 (2950 4525)(3100 4525);
WIRE 16 -1 (3100 4525)(3100 4200);
WIRE 16 -1 (3100 4125)(3100 4200);
WIRE 16 -1 (2700 4200)(3100 4200);
WIRE 16 -1 (2700 4125)(2700 4200);
WIRE 16 -1 (2700 4250)(2700 4200);
WIRE 16 -1 (2325 2500)(2325 2625);
WIRE 16 -1 (2675 2625)(2325 2625);
WIRE 16 -1 (2675 2500)(2675 2625);
WIRE 16 -1 (2675 2650)(2675 2625);
WIRE 16 -1 (-1125 2000)(-1125 1950);
WIRE 16 -1 (-1350 750)(-1350 725);
WIRE 16 -1 (2250 4525)(2175 4525);
WIRE 16 -1 (2175 4525)(2175 4500);
WIRE 16 -1 (3100 3750)(3100 3925);
WIRE 16 -1 (2700 3750)(3100 3750);
WIRE 16 -1 (2700 3925)(2700 3750);
WIRE 16 -1 (2700 3725)(2700 3750);
WIRE 16 -1 (275 3900)(275 4025);
WIRE 16 -1 (275 4025)(575 4025);
WIRE 16 -1 (875 4025)(575 4025);
WIRE 16 -1 (575 4025)(575 3900);
WIRE 16 -1 (875 3925)(875 4025);
WIRE 16 -1 (1175 4025)(875 4025);
WIRE 16 -1 (1175 4100)(1175 4025);
WIRE 16 -1 (1175 4025)(1175 3900);
WIRE 16 -1 (875 1000)(875 850);
WIRE 16 -1 (875 850)(500 850);
WIRE 16 -1 (500 1000)(500 850);
WIRE 16 -1 (500 775)(500 850);
WIRE 16 -1 (-1950 3500)(-1950 3400);
WIRE 16 -1 (-1950 3400)(-2325 3400);
WIRE 16 -1 (-2325 3500)(-2325 3400);
WIRE 16 -1 (-2325 3400)(-2700 3400);
WIRE 16 -1 (-2700 3350)(-2700 3400);
WIRE 16 -1 (-2700 3400)(-2700 3500);
WIRE 16 -1 (-2400 1550)(-3125 1550);
FORCEPROP 2 LAST SIG_NAME XDP_PREQ_N
J 0
(-3100 1560);
DISPLAY 0.617021 (-3100 1560);
PAINT ORANGE (-3100 1560);
WIRE 16 -1 (-2400 1350)(-3125 1350);
FORCEPROP 2 LAST SIG_NAME XDP_PRDY_N
J 0
(-3100 1360);
DISPLAY 0.617021 (-3100 1360);
PAINT ORANGE (-3100 1360);
WIRE 16 -1 (-2400 1150)(-3125 1150);
FORCEPROP 2 LAST SIG_NAME XDP_OBSFN_B0_MBP6_N
J 0
(-3100 1160);
DISPLAY 0.617021 (-3100 1160);
PAINT ORANGE (-3100 1160);
WIRE 16 -1 (-2400 950)(-3125 950);
FORCEPROP 2 LAST SIG_NAME XDP_OBSFN_B1_MBP7_N
J 0
(-3100 960);
DISPLAY 0.617021 (-3100 960);
PAINT ORANGE (-3100 960);
WIRE 16 -1 (-2400 2675)(-2500 2675);
WIRE 16 -1 (-2500 2675)(-2500 2475);
WIRE 16 -1 (-2500 2475)(-2400 2475);
WIRE 16 -1 (-2500 2475)(-2500 2275);
WIRE 16 -1 (-2500 2275)(-2400 2275);
WIRE 16 -1 (-2500 2275)(-2500 2075);
WIRE 16 -1 (-2500 2075)(-2400 2075);
WIRE 16 -1 (-2500 2075)(-2500 1450);
WIRE 16 -1 (-2400 1450)(-2500 1450);
WIRE 16 -1 (-2500 1450)(-2500 1250);
WIRE 16 -1 (-2500 1250)(-2400 1250);
WIRE 16 -1 (-2500 1250)(-2500 1050);
WIRE 16 -1 (-2500 1050)(-2400 1050);
WIRE 16 -1 (-2500 1050)(-2500 850);
WIRE 16 -1 (-2500 850)(-2400 850);
WIRE 16 -1 (-3125 850)(-2500 850);
FORCEPROP 2 LAST SIG_NAME PWRGD_PVCCIN_CPU0
J 0
(-3100 868);
DISPLAY 0.617021 (-3100 868);
PAINT ORANGE (-3100 868);
WIRE 16 -1 (-2400 2775)(-3125 2775);
FORCEPROP 2 LAST SIG_NAME XDP_TDI
J 0
(-3085 2785);
DISPLAY 0.617021 (-3085 2785);
PAINT ORANGE (-3085 2785);
WIRE 16 -1 (-2400 2575)(-3125 2575);
FORCEPROP 2 LAST SIG_NAME XDP_TDO
J 0
(-3085 2585);
DISPLAY 0.617021 (-3085 2585);
PAINT ORANGE (-3085 2585);
WIRE 16 -1 (-2400 2375)(-3125 2375);
FORCEPROP 2 LAST SIG_NAME XDP_TMS
J 0
(-3085 2385);
DISPLAY 0.617021 (-3085 2385);
PAINT ORANGE (-3085 2385);
WIRE 16 -1 (-2400 2175)(-3125 2175);
FORCEPROP 2 LAST SIG_NAME XDP_TRST_N
J 0
(-3085 2185);
DISPLAY 0.617021 (-3085 2185);
PAINT ORANGE (-3085 2185);
WIRE 16 -1 (-2700 3700)(-2700 3725);
WIRE 16 -1 (-2700 3725)(-3150 3725);
FORCEPROP 2 LAST SIG_NAME XDP_PCH_TCK1
J 0
(-3100 3735);
DISPLAY 0.617021 (-3100 3735);
PAINT ORANGE (-3100 3735);
WIRE 16 -1 (-2325 3800)(-2325 3700);
WIRE 16 -1 (-3150 3800)(-2325 3800);
FORCEPROP 2 LAST SIG_NAME XDP_TRST_N
J 0
(-3100 3810);
DISPLAY 0.617021 (-3100 3810);
PAINT ORANGE (-3100 3810);
WIRE 16 -1 (-1275 950)(-2000 950);
FORCEPROP 2 LAST SIG_NAME XDP_CPU_OBSFN_B1_MBP7_N
J 0
(-1910 960);
DISPLAY 0.617021 (-1910 960);
PAINT ORANGE (-1910 960);
WIRE 16 -1 (-1275 1550)(-2000 1550);
FORCEPROP 2 LAST SIG_NAME XDP_CPU_PREQ_N
J 0
(-1910 1560);
DISPLAY 0.617021 (-1910 1560);
PAINT ORANGE (-1910 1560);
WIRE 16 -1 (-1275 1350)(-2000 1350);
FORCEPROP 2 LAST SIG_NAME XDP_CPU_PRDY_N
J 0
(-1910 1360);
DISPLAY 0.617021 (-1910 1360);
PAINT ORANGE (-1910 1360);
WIRE 16 -1 (-1275 1150)(-2000 1150);
FORCEPROP 2 LAST SIG_NAME XDP_CPU_OBSFN_B0_MBP6_N
J 0
(-1910 1160);
DISPLAY 0.617021 (-1910 1160);
PAINT ORANGE (-1910 1160);
WIRE 16 273 (-725 3075)(-725 725);
WIRE 16 -1 (-1275 2775)(-2000 2775);
FORCEPROP 2 LAST SIG_NAME XDP_CPU_TDI
J 0
(-1910 2785);
DISPLAY 0.617021 (-1910 2785);
PAINT ORANGE (-1910 2785);
WIRE 16 -1 (-1275 2575)(-2000 2575);
FORCEPROP 2 LAST SIG_NAME XDP_CPU_TDO
J 0
(-1910 2585);
DISPLAY 0.617021 (-1910 2585);
PAINT ORANGE (-1910 2585);
WIRE 16 -1 (-1275 2375)(-2000 2375);
FORCEPROP 2 LAST SIG_NAME XDP_CPU_TMS
J 0
(-1910 2385);
DISPLAY 0.617021 (-1910 2385);
PAINT ORANGE (-1910 2385);
WIRE 16 -1 (-1275 2175)(-2000 2175);
FORCEPROP 2 LAST SIG_NAME XDP_CPU_TRST_N
J 0
(-1910 2185);
DISPLAY 0.617021 (-1910 2185);
PAINT ORANGE (-1910 2185);
WIRE 16 -1 (-1950 3700)(-1950 3875);
WIRE 16 -1 (-1950 3875)(-3150 3875);
FORCEPROP 2 LAST SIG_NAME XDP_PCH_CPU_TCK0
J 0
(-3100 3885);
DISPLAY 0.617021 (-3100 3885);
PAINT ORANGE (-3100 3885);
WIRE 16 -1 (-1200 4325)(-1200 3950);
WIRE 16 -1 (-1200 3950)(-3150 3950);
FORCEPROP 2 LAST SIG_NAME XDP_PRDY_N
J 0
(-3100 3960);
DISPLAY 0.617021 (-3100 3960);
PAINT ORANGE (-3100 3960);
WIRE 16 -1 (-1575 4325)(-1575 4025);
WIRE 16 -1 (-1575 4025)(-3150 4025);
FORCEPROP 2 LAST SIG_NAME XDP_PREQ_N
J 0
(-3100 4035);
DISPLAY 0.617021 (-3100 4035);
PAINT ORANGE (-3100 4035);
WIRE 16 273 (-850 5150)(-850 3200);
WIRE 16 -1 (-2700 4250)(-2700 4325);
WIRE 16 -1 (-2700 4250)(-3150 4250);
FORCEPROP 2 LAST SIG_NAME XDP_TMS
J 0
(-3100 4260);
DISPLAY 0.617021 (-3100 4260);
PAINT ORANGE (-3100 4260);
WIRE 16 -1 (-2325 4175)(-2325 4325);
WIRE 16 -1 (-2325 4175)(-3150 4175);
FORCEPROP 2 LAST SIG_NAME XDP_TDI
J 0
(-3100 4185);
DISPLAY 0.617021 (-3100 4185);
PAINT ORANGE (-3100 4185);
WIRE 16 -1 (-1975 5100)(-1975 4900);
WIRE 16 -1 (-1975 5100)(-3575 5100);
WIRE 16 -1 (-3575 4900)(-1975 4900);
WIRE 16 -1 (-3575 5100)(-3575 4900);
WIRE 16 -1 (-1950 5125)(-1950 4875);
WIRE 16 -1 (-1950 5125)(-3600 5125);
WIRE 16 -1 (-1950 4875)(-3600 4875);
WIRE 16 -1 (-3600 5125)(-3600 4875);
WIRE 16 -1 (-1950 4325)(-1950 4100);
WIRE 16 -1 (-1950 4100)(-3150 4100);
FORCEPROP 2 LAST SIG_NAME XDP_TDO
J 0
(-3100 4110);
DISPLAY 0.617021 (-3100 4110);
PAINT ORANGE (-3100 4110);
WIRE 16 273 (4200 3150)(-3650 3150);
WIRE 16 -1 (900 4850)(900 4650);
WIRE 16 -1 (900 4850)(-700 4850);
WIRE 16 -1 (-700 4650)(900 4650);
WIRE 16 -1 (-700 4850)(-700 4650);
WIRE 16 -1 (925 4875)(925 4625);
WIRE 16 -1 (925 4875)(-725 4875);
WIRE 16 -1 (925 4625)(-725 4625);
WIRE 16 -1 (-725 4875)(-725 4625);
WIRE 16 -1 (1450 3000)(1450 2800);
WIRE 16 -1 (1450 3000)(-150 3000);
WIRE 16 -1 (-150 2800)(1450 2800);
WIRE 16 -1 (-150 3000)(-150 2800);
WIRE 16 -1 (1475 3025)(1475 2775);
WIRE 16 -1 (1475 3025)(-175 3025);
WIRE 16 -1 (1475 2775)(-175 2775);
WIRE 16 -1 (-175 3025)(-175 2775);
WIRE 16 -1 (500 1350)(500 1200);
WIRE 16 -1 (-50 1350)(500 1350);
FORCEPROP 2 LAST SIG_NAME XDP_CPU_TRST_N
J 0
(-10 1360);
DISPLAY 0.617021 (-10 1360);
PAINT ORANGE (-10 1360);
WIRE 16 -1 (875 1200)(875 1425);
WIRE 16 -1 (875 1425)(-50 1425);
FORCEPROP 2 LAST SIG_NAME XDP_CPU_TCK0
J 0
(-10 1435);
DISPLAY 0.617021 (-10 1435);
PAINT ORANGE (-10 1435);
WIRE 16 -1 (1950 2300)(1950 1950);
WIRE 16 -1 (1950 1950)(-50 1950);
FORCEPROP 2 LAST SIG_NAME XDP_CPU_PRDY_N
J 0
(-10 1960);
DISPLAY 0.617021 (-10 1960);
PAINT ORANGE (-10 1960);
WIRE 16 -1 (1600 2300)(1600 2025);
WIRE 16 -1 (1600 2025)(-50 2025);
FORCEPROP 2 LAST SIG_NAME XDP_CPU_PREQ_N
J 0
(-10 2035);
DISPLAY 0.617021 (-10 2035);
PAINT ORANGE (-10 2035);
WIRE 16 -1 (500 2250)(500 2300);
WIRE 16 -1 (500 2250)(-50 2250);
FORCEPROP 2 LAST SIG_NAME XDP_CPU_TMS
J 0
(-10 2260);
DISPLAY 0.617021 (-10 2260);
PAINT ORANGE (-10 2260);
WIRE 16 -1 (875 2175)(875 2300);
WIRE 16 -1 (875 2175)(-50 2175);
FORCEPROP 2 LAST SIG_NAME XDP_CPU1_TDI
J 0
(-10 2185);
DISPLAY 0.617021 (-10 2185);
PAINT ORANGE (-10 2185);
WIRE 16 -1 (275 3650)(275 3700);
WIRE 16 -1 (275 3650)(-250 3650);
FORCEPROP 2 LAST SIG_NAME XDP_CPU_TDI
J 0
(-225 3660);
DISPLAY 0.617021 (-225 3660);
PAINT ORANGE (-225 3660);
WIRE 16 -1 (575 3700)(575 3575);
WIRE 16 -1 (575 3575)(-250 3575);
FORCEPROP 2 LAST SIG_NAME XDP_CPU0_TDO
J 0
(-225 3585);
DISPLAY 0.617021 (-225 3585);
PAINT ORANGE (-225 3585);
WIRE 16 -1 (875 3725)(875 3500);
WIRE 16 -1 (875 3500)(-250 3500);
FORCEPROP 2 LAST SIG_NAME XDP_CPU_MBP0_N
J 0
(-225 3510);
DISPLAY 0.617021 (-225 3510);
PAINT ORANGE (-225 3510);
WIRE 16 -1 (1225 2300)(1225 2100);
WIRE 16 -1 (1225 2100)(-50 2100);
FORCEPROP 2 LAST SIG_NAME XDP_CPU1_TDO
J 0
(-10 2110);
DISPLAY 0.617021 (-10 2110);
PAINT ORANGE (-10 2110);
WIRE 16 -1 (1175 3700)(1175 3425);
WIRE 16 -1 (1175 3425)(-250 3425);
FORCEPROP 2 LAST SIG_NAME XDP_CPU_MBP1_N
J 0
(-225 3435);
DISPLAY 0.617021 (-225 3435);
PAINT ORANGE (-225 3435);
WIRE 16 682 (2375 1300)(2375 900);
WIRE 16 682 (425 1300)(2375 1300);
WIRE 16 682 (2375 900)(425 900);
WIRE 16 682 (425 900)(425 1300);
WIRE 16 -1 (3500 2300)(3500 1500);
WIRE 16 -1 (-50 1500)(3500 1500);
FORCEPROP 2 LAST SIG_NAME XDP_CPU_OBSFN_B1_MBP7_N
J 0
(-10 1510);
DISPLAY 0.617021 (-10 1510);
PAINT ORANGE (-10 1510);
WIRE 16 -1 (2325 2300)(2325 1875);
WIRE 16 -1 (2325 1875)(-50 1875);
FORCEPROP 2 LAST SIG_NAME XDP_CPU_MBP0_N
J 0
(-10 1885);
DISPLAY 0.617021 (-10 1885);
PAINT ORANGE (-10 1885);
WIRE 16 -1 (2675 2300)(2675 1800);
WIRE 16 -1 (2675 1800)(-50 1800);
FORCEPROP 2 LAST SIG_NAME XDP_CPU_MBP1_N
J 0
(-10 1810);
DISPLAY 0.617021 (-10 1810);
PAINT ORANGE (-10 1810);
WIRE 16 -1 (3175 2300)(3175 1575);
WIRE 16 -1 (-50 1575)(3175 1575);
FORCEPROP 2 LAST SIG_NAME XDP_CPU_OBSFN_B0_MBP6_N
J 0
(-10 1585);
DISPLAY 0.617021 (-10 1585);
PAINT ORANGE (-10 1585);
WIRE 16 -1 (2825 3425)(2200 3425);
FORCEPROP 2 LAST SIG_NAME XDP_CPU0_TDO
J 0
(2190 3435);
DISPLAY 0.617021 (2190 3435);
PAINT ORANGE (2190 3435);
WIRE 16 -1 (2825 3375)(2200 3375);
FORCEPROP 2 LAST SIG_NAME FM_CPU1_SKTOCC_LVT3_N
J 0
(2190 3385);
DISPLAY 0.617021 (2190 3385);
PAINT ORANGE (2190 3385);
WIRE 16 -1 (3325 3425)(3725 3425);
FORCEPROP 2 LAST SIG_NAME XDP_CPU1_TDI
J 0
(3390 3435);
DISPLAY 0.617021 (3390 3435);
PAINT ORANGE (3390 3435);
WIRE 16 273 (1075 4400)(1075 5150);
WIRE 16 273 (1550 4400)(1075 4400);
WIRE 16 273 (1550 4400)(1550 3300);
WIRE 16 -1 (1825 4675)(2250 4675);
FORCEPROP 2 LAST SIG_NAME XDP_CPU_TDO
J 0
(1815 4685);
DISPLAY 0.617021 (1815 4685);
PAINT ORANGE (1815 4685);
WIRE 16 -1 (2950 4725)(3600 4725);
FORCEPROP 2 LAST SIG_NAME XDP_CPU1_TDO
J 0
(3025 4735);
DISPLAY 0.617021 (3025 4735);
PAINT ORANGE (3025 4735);
WIRE 16 -1 (2950 4625)(3600 4625);
FORCEPROP 2 LAST SIG_NAME XDP_CPU0_TDO
J 0
(3025 4635);
DISPLAY 0.617021 (3025 4635);
PAINT ORANGE (3025 4635);
WIRE 16 -1 (3600 4825)(2950 4825);
FORCEPROP 2 LAST SIG_NAME FM_CPU1_SKTOCC_LVT3_N
J 0
(3025 4835);
DISPLAY 0.617021 (3025 4835);
PAINT ORANGE (3025 4835);
DOT 1 (-2500 2275);
DOT 1 (1950 2625);
DOT 1 (1225 2575);
DOT 1 (575 4025);
DOT 1 (-1200 4650);
DOT 1 (2675 2625);
DOT 1 (-2500 2075);
DOT 1 (-2325 3400);
DOT 1 (-2700 3400);
DOT 1 (1175 4025);
DOT 1 (-2500 1050);
DOT 1 (-2500 850);
DOT 1 (-2500 1250);
DOT 1 (-2500 2475);
DOT 1 (-2325 4650);
DOT 1 (-1950 4650);
DOT 1 (-1575 4650);
DOT 1 (500 850);
DOT 1 (2700 3750);
DOT 1 (875 4025);
DOT 1 (2700 4200);
DOT 1 (-2500 1450);
DOT 1 (3500 2600);
DOT 1 (3100 4200);
FORCENOTE
74CBTLVG125 VCC PIN
(3675 3700) 0;
DISPLAY LEFT (3675 3700);
DISPLAY 0.808511 (3675 3700);
PAINT PURPLE (3675 3700);
FORCENOTE
PLACE NEAR 
(3675 3750) 0;
DISPLAY LEFT (3675 3750);
DISPLAY 0.808511 (3675 3750);
PAINT PURPLE (3675 3750);
FORCENOTE
CPU1 XDP TERMINATIONS
(75 2875) 0;
DISPLAY LEFT (75 2875);
DISPLAY 1.170213 (75 2875);
PAINT PURPLE (75 2875);
FORCENOTE
CPU0 XDP TERMINATIONS
(-475 4725) 0;
DISPLAY LEFT (-475 4725);
DISPLAY 1.170213 (-475 4725);
PAINT PURPLE (-475 4725);
FORCENOTE
PCH XDP TERMINATIONS
(-3350 4975) 0;
DISPLAY LEFT (-3350 4975);
DISPLAY 1.170213 (-3350 4975);
PAINT PURPLE (-3350 4975);
FORCENOTE
ROOM=DEBUG
(-3651 361) 0;
DISPLAY LEFT (-3651 361);
PAINT PURPLE (-3651 361);
QUIT
